FILE_TYPE = MACRO_DRAWING;
SET COLOR_WIRE YELLOW;
SET COLOR_PROP MONO;
SET COLOR_DOT WHITE;
SET COLOR_ARC YELLOW;
SET COLOR_BODY GREEN;
SET COLOR_NOTE MONO;
SET PROP_DISPLAY VALUE;
SET PAGE_NUMBER P241;
FORCEADD OFFPAGE..2
(3025 4625);
FORCEPROP 2 LAST $XR0 240 
J 0
(3214 4625);
DISPLAY 0.638298 (3214 4625);
PAINT MONO (3214 4625);
FORCEPROP 2 LAST PATH I1
J 0
(3375 4665);
DISPLAY 1.021277 (3375 4665);
PAINT ORANGE (3375 4665);
DISPLAY INVISIBLE (3375 4665);
FORCEPROP 2 LAST CDS_LIB mstr_standard
J 0
(3025 4625);
PAINT MONO (3025 4625);
DISPLAY INVISIBLE (3025 4625);
FORCEPROP 1 LAST OFFPAGE TRUE
J 0
(3350 4500);
DISPLAY 1.170213 (3350 4500);
PAINT GREEN (3350 4500);
DISPLAY INVISIBLE (3350 4500);
FORCEPROP 1 LAST COMMENT_BODY TRUE
J 0
(2980 4530);
DISPLAY 1.170213 (2980 4530);
PAINT GREEN (2980 4530);
DISPLAY INVISIBLE (2980 4530);
FORCEADD ST220U10VDM-LGP..1
(2850 3825);
FORCEPROP 2 LASTPIN (2850 3900) $PN 1
R 1
J 0
(2840 3910);
DISPLAY 0.808511 (2840 3910);
PAINT ORANGE (2840 3910);
FORCEPROP 2 LAST PACK_SIZE ESR=25MOHM
J 0
(2950 3675);
DISPLAY 0.638298 (2950 3675);
PAINT GREEN (2950 3675);
FORCEPROP 2 LAST TYPE TMAX=105C
J 0
(2950 3725);
DISPLAY 0.638298 (2950 3725);
PAINT GREEN (2950 3725);
FORCEPROP 2 LAST RATED 10V
J 0
(2950 3775);
DISPLAY 0.638298 (2950 3775);
PAINT GREEN (2950 3775);
FORCEPROP 2 LAST TOLERANCE IRP=2400MA
J 0
(2950 3825);
DISPLAY 0.638298 (2950 3825);
PAINT GREEN (2950 3825);
FORCEPROP 2 LAST ATTRIBUTE 220UF
J 0
(2950 3875);
DISPLAY 0.638298 (2950 3875);
PAINT GREEN (2950 3875);
FORCEPROP 1 LAST LOCATION C8E4
J 0
(2950 3930);
DISPLAY 0.617021 (2950 3930);
PAINT GREEN (2950 3930);
FORCEPROP 1 LAST VALUE ST220U10VDM-LGP
R 1
J 0
(2925 3600);
DISPLAY 0.617021 (2925 3600);
PAINT GREEN (2925 3600);
FORCEPROP 2 LASTPIN (2850 3750) $PN 2
R 1
J 2
(2840 3740);
DISPLAY 0.808511 (2840 3740);
PAINT ORANGE (2840 3740);
FORCEPROP 1 LAST PACK_TYPE SMD-TCG
J 0
(2850 3825);
DISPLAY 0.617021 (2850 3825);
PAINT GREEN (2850 3825);
DISPLAY INVISIBLE (2850 3825);
FORCEPROP 2 LAST SEC 1
J 0
(2875 3900);
DISPLAY 0.680851 (2875 3900);
PAINT MONO (2875 3900);
DISPLAY INVISIBLE (2875 3900);
FORCEPROP 2 LAST SEC_TYPE SMD-TCG
J 0
(2875 3900);
DISPLAY 1.021277 (2875 3900);
PAINT ORANGE (2875 3900);
DISPLAY INVISIBLE (2875 3900);
FORCEPROP 1 LAST CDS_LMAN_SYM_OUTLINE -50,25,50,-25
J 0
(2850 3825);
DISPLAY 0.468085 (2850 3825);
PAINT GREEN (2850 3825);
DISPLAY INVISIBLE (2850 3825);
FORCEPROP 1 LAST PATH I100
J 0
(2850 3865);
DISPLAY 0.617021 (2850 3865);
PAINT GREEN (2850 3865);
DISPLAY INVISIBLE (2850 3865);
FORCEPROP 2 LAST CDS_LIB w_hdl
J 0
(2850 3825);
PAINT MONO (2850 3825);
DISPLAY INVISIBLE (2850 3825);
FORCEPROP 1 LAST PART_NUMBER 77.22271.L03
J 0
(2850 3785);
DISPLAY 0.617021 (2850 3785);
PAINT GREEN (2850 3785);
DISPLAY INVISIBLE (2850 3785);
FORCEADD SC22U16V5MX-4-GP..1
(3400 3825);
FORCEPROP 1 LAST VALUE SC22U16V5MX-4-GP
R 1
J 0
(3475 3595);
DISPLAY 0.617021 (3475 3595);
PAINT GREEN (3475 3595);
FORCEPROP 2 LAST PACK_SIZE 0805
J 0
(3500 3675);
DISPLAY 0.638298 (3500 3675);
PAINT GREEN (3500 3675);
FORCEPROP 2 LASTPIN (3400 3900) $PN 1
R 1
J 0
(3390 3910);
DISPLAY 0.808511 (3390 3910);
PAINT ORANGE (3390 3910);
FORCEPROP 2 LAST RATED 16V
J 0
(3500 3775);
DISPLAY 0.638298 (3500 3775);
PAINT GREEN (3500 3775);
FORCEPROP 2 LAST TYPE X6S
J 0
(3500 3725);
DISPLAY 0.638298 (3500 3725);
PAINT GREEN (3500 3725);
FORCEPROP 2 LASTPIN (3400 3750) $PN 2
R 1
J 2
(3390 3740);
DISPLAY 0.808511 (3390 3740);
PAINT ORANGE (3390 3740);
FORCEPROP 2 LAST ATTRIBUTE 22UF
J 0
(3500 3875);
DISPLAY 0.638298 (3500 3875);
PAINT GREEN (3500 3875);
FORCEPROP 2 LAST TOLERANCE 20%
J 0
(3500 3825);
DISPLAY 0.638298 (3500 3825);
PAINT GREEN (3500 3825);
FORCEPROP 1 LAST LOCATION C8E7
J 0
(3500 3935);
DISPLAY 0.617021 (3500 3935);
PAINT GREEN (3500 3935);
FORCEPROP 0 LAST CDS_SEC 1
J 0
(3450 3925);
PAINT MONO (3450 3925);
DISPLAY INVISIBLE (3450 3925);
FORCEPROP 1 LAST PACK_TYPE SMD-BCG5
J 0
(3400 3825);
DISPLAY 0.617021 (3400 3825);
PAINT GREEN (3400 3825);
DISPLAY INVISIBLE (3400 3825);
FORCEPROP 2 LAST SEC 1
J 0
(3425 3900);
DISPLAY 0.680851 (3425 3900);
PAINT MONO (3425 3900);
DISPLAY INVISIBLE (3425 3900);
FORCEPROP 2 LAST SEC_TYPE SMD-BCG5
J 0
(3425 3900);
DISPLAY 1.021277 (3425 3900);
PAINT ORANGE (3425 3900);
DISPLAY INVISIBLE (3425 3900);
FORCEPROP 1 LAST PART_NUMBER 078.22611.0811
J 0
(3400 3825);
DISPLAY 0.617021 (3400 3825);
PAINT GREEN (3400 3825);
DISPLAY INVISIBLE (3400 3825);
FORCEPROP 2 LAST CDS_LIB w_hdl
J 0
(3400 3825);
PAINT MONO (3400 3825);
DISPLAY INVISIBLE (3400 3825);
FORCEPROP 1 LAST CDS_LMAN_SYM_OUTLINE -50,25,50,-25
J 0
(3400 3825);
DISPLAY 0.468085 (3400 3825);
PAINT GREEN (3400 3825);
DISPLAY INVISIBLE (3400 3825);
FORCEPROP 1 LAST PATH I103
J 0
(3400 3825);
DISPLAY 0.617021 (3400 3825);
PAINT GREEN (3400 3825);
DISPLAY INVISIBLE (3400 3825);
FORCEPROP 0 LAST CDS_LOCATION C8E7
J 0
(3450 3925);
PAINT MONO (3450 3925);
DISPLAY INVISIBLE (3450 3925);
FORCEADD SC22U16V5MX-4-GP..1
(3800 3825);
FORCEPROP 2 LASTPIN (3800 3900) $PN 1
R 1
J 0
(3790 3910);
DISPLAY 0.808511 (3790 3910);
PAINT ORANGE (3790 3910);
FORCEPROP 2 LAST ATTRIBUTE 22UF
J 0
(3900 3875);
DISPLAY 0.638298 (3900 3875);
PAINT GREEN (3900 3875);
FORCEPROP 2 LAST TOLERANCE 20%
J 0
(3900 3825);
DISPLAY 0.638298 (3900 3825);
PAINT GREEN (3900 3825);
FORCEPROP 2 LAST RATED 16V
J 0
(3900 3775);
DISPLAY 0.638298 (3900 3775);
PAINT GREEN (3900 3775);
FORCEPROP 2 LAST TYPE X6S
J 0
(3900 3725);
DISPLAY 0.638298 (3900 3725);
PAINT GREEN (3900 3725);
FORCEPROP 2 LAST PACK_SIZE 0805
J 0
(3900 3675);
DISPLAY 0.638298 (3900 3675);
PAINT GREEN (3900 3675);
FORCEPROP 2 LASTPIN (3800 3750) $PN 2
R 1
J 2
(3790 3740);
DISPLAY 0.808511 (3790 3740);
PAINT ORANGE (3790 3740);
FORCEPROP 1 LAST LOCATION C8E9
J 0
(3900 3935);
DISPLAY 0.617021 (3900 3935);
PAINT GREEN (3900 3935);
FORCEPROP 1 LAST VALUE SC22U16V5MX-4-GP
R 1
J 0
(3875 3595);
DISPLAY 0.617021 (3875 3595);
PAINT GREEN (3875 3595);
FORCEPROP 0 LAST CDS_LOCATION C8E9
J 0
(3850 3925);
PAINT MONO (3850 3925);
DISPLAY INVISIBLE (3850 3925);
FORCEPROP 0 LAST CDS_SEC 1
J 0
(3850 3925);
PAINT MONO (3850 3925);
DISPLAY INVISIBLE (3850 3925);
FORCEPROP 1 LAST PACK_TYPE SMD-BCG5
J 0
(3800 3825);
DISPLAY 0.617021 (3800 3825);
PAINT GREEN (3800 3825);
DISPLAY INVISIBLE (3800 3825);
FORCEPROP 2 LAST SEC 1
J 0
(3825 3900);
DISPLAY 0.680851 (3825 3900);
PAINT MONO (3825 3900);
DISPLAY INVISIBLE (3825 3900);
FORCEPROP 2 LAST SEC_TYPE SMD-BCG5
J 0
(3825 3900);
DISPLAY 1.021277 (3825 3900);
PAINT ORANGE (3825 3900);
DISPLAY INVISIBLE (3825 3900);
FORCEPROP 1 LAST PART_NUMBER 078.22611.0811
J 0
(3800 3825);
DISPLAY 0.617021 (3800 3825);
PAINT GREEN (3800 3825);
DISPLAY INVISIBLE (3800 3825);
FORCEPROP 2 LAST CDS_LIB w_hdl
J 0
(3800 3825);
PAINT MONO (3800 3825);
DISPLAY INVISIBLE (3800 3825);
FORCEPROP 1 LAST CDS_LMAN_SYM_OUTLINE -50,25,50,-25
J 0
(3800 3825);
DISPLAY 0.468085 (3800 3825);
PAINT GREEN (3800 3825);
DISPLAY INVISIBLE (3800 3825);
FORCEPROP 1 LAST PATH I104
J 0
(3800 3825);
DISPLAY 0.617021 (3800 3825);
PAINT GREEN (3800 3825);
DISPLAY INVISIBLE (3800 3825);
FORCEADD RES..2
(1225 4850);
FORCEPROP 1 LAST WATTAGE 1/16W
J 0
(1265 4775);
DISPLAY 0.617021 (1265 4775);
PAINT SKYBLUE (1265 4775);
FORCEPROP 1 LAST VALUE 1.00K
J 0
(1270 4875);
DISPLAY 0.617021 (1270 4875);
PAINT SKYBLUE (1270 4875);
FORCEPROP 1 LAST TOLERANCE 1%
J 0
(1270 4825);
DISPLAY 0.617021 (1270 4825);
PAINT SKYBLUE (1270 4825);
FORCEPROP 1 LAST MATERIAL CHIP
J 0
(1265 4725);
DISPLAY 0.617021 (1265 4725);
PAINT SKYBLUE (1265 4725);
FORCEPROP 1 LAST PACK_TYPE 0402
J 0
(1265 4675);
DISPLAY 0.617021 (1265 4675);
PAINT SKYBLUE (1265 4675);
FORCEPROP 1 LAST LOCATION R7E12
J 0
(1270 4925);
DISPLAY 0.617021 (1270 4925);
PAINT AQUA (1270 4925);
FORCEPROP 1 LASTPIN (1225 4950) $PN 1
J 0
(1230 4912);
DISPLAY 0.617021 (1230 4912);
PAINT WHITE (1230 4912);
FORCEPROP 1 LAST PART_NUMBER G21796-026
R 1
J 0
(1190 4650);
DISPLAY 0.617021 (1190 4650);
PAINT BLUE (1190 4650);
FORCEPROP 1 LASTPIN (1225 4750) $PN 2
J 0
(1230 4760);
DISPLAY 0.617021 (1230 4760);
PAINT WHITE (1230 4760);
FORCEPROP 2 LAST SEC_TYPE 0402
J 0
(1275 5075);
DISPLAY 1.361702 (1275 5075);
PAINT ORANGE (1275 5075);
DISPLAY INVISIBLE (1275 5075);
FORCEPROP 2 LAST REUSE_ID 21
J 0
(1275 5075);
DISPLAY 1.361702 (1275 5075);
PAINT ORANGE (1275 5075);
DISPLAY INVISIBLE (1275 5075);
FORCEPROP 2 LAST BOM_COST P5V_STBY_VR
J 0
(1275 5025);
DISPLAY 1.021277 (1275 5025);
PAINT ORANGE (1275 5025);
DISPLAY INVISIBLE (1275 5025);
FORCEPROP 2 LAST SEC 1
J 0
(1275 5075);
DISPLAY 0.914894 (1275 5075);
PAINT MONO (1275 5075);
DISPLAY INVISIBLE (1275 5075);
FORCEPROP 1 LAST PATH I11
J 0
(1275 5025);
DISPLAY 0.978723 (1275 5025);
PAINT WHITE (1275 5025);
DISPLAY INVISIBLE (1275 5025);
FORCEPROP 2 LAST ROOM P5V_STBY_VR
J 0
(1275 4975);
DISPLAY 1.021277 (1275 4975);
PAINT ORANGE (1275 4975);
DISPLAY INVISIBLE (1275 4975);
FORCEPROP 2 LAST CDS_LOCATION R7E12
J 0
(1270 4925);
DISPLAY 0.617021 (1270 4925);
PAINT AQUA (1270 4925);
DISPLAY INVISIBLE (1270 4925);
FORCEPROP 2 LAST CDS_LIB mstr_discrete
J 0
(1225 4850);
DISPLAY 1.340426 (1225 4850);
PAINT ORANGE (1225 4850);
DISPLAY INVISIBLE (1225 4850);
FORCEADD CAP..2
(1200 3675);
FORCEPROP 1 LAST MATERIAL X7R
J 0
(1350 3600);
DISPLAY 0.617021 (1350 3600);
PAINT SKYBLUE (1350 3600);
FORCEPROP 1 LAST VOLTAGE 25V
J 0
(1250 3625);
DISPLAY 0.617021 (1250 3625);
PAINT SKYBLUE (1250 3625);
FORCEPROP 1 LASTPIN (1300 3675) $PN 2
J 0
(1260 3690);
DISPLAY 0.617021 (1260 3690);
PAINT WHITE (1260 3690);
FORCEPROP 1 LAST PACK_TYPE 0603LF
J 1
(1375 3700);
DISPLAY 0.617021 (1375 3700);
PAINT SKYBLUE (1375 3700);
FORCEPROP 1 LAST LOCATION C8E6
J 1
(1200 3725);
DISPLAY 0.617021 (1200 3725);
PAINT AQUA (1200 3725);
FORCEPROP 1 LASTPIN (1100 3675) $PN 1
J 0
(1090 3690);
DISPLAY 0.617021 (1090 3690);
PAINT WHITE (1090 3690);
FORCEPROP 1 LAST PART_NUMBER 602433-020
J 1
(1200 3575);
DISPLAY 0.617021 (1200 3575);
PAINT BLUE (1200 3575);
FORCEPROP 1 LAST TOLERANCE 10%
J 2
(1075 3600);
DISPLAY 0.617021 (1075 3600);
PAINT SKYBLUE (1075 3600);
FORCEPROP 1 LAST VALUE 0.1UF
J 2
(1175 3625);
DISPLAY 0.617021 (1175 3625);
PAINT SKYBLUE (1175 3625);
FORCEPROP 2 LAST SEC_TYPE 0603LF
J 2
(1200 3925);
DISPLAY 1.361702 (1200 3925);
PAINT ORANGE (1200 3925);
DISPLAY INVISIBLE (1200 3925);
FORCEPROP 2 LAST SEC 1
J 2
(1200 3925);
DISPLAY 0.914894 (1200 3925);
PAINT MONO (1200 3925);
DISPLAY INVISIBLE (1200 3925);
FORCEPROP 0 LAST SPOF TRUE
J 0
(1200 3875);
DISPLAY 1.361702 (1200 3875);
PAINT ORANGE (1200 3875);
DISPLAY INVISIBLE (1200 3875);
FORCEPROP 1 LAST PATH I12
J 0
(1200 3875);
DISPLAY 0.978723 (1200 3875);
PAINT WHITE (1200 3875);
DISPLAY INVISIBLE (1200 3875);
FORCEPROP 2 LAST REUSE_ID 27
J 2
(1200 3925);
DISPLAY 1.361702 (1200 3925);
PAINT ORANGE (1200 3925);
DISPLAY INVISIBLE (1200 3925);
FORCEPROP 2 LAST BOM_COST P5V_STBY_VR
J 0
(1200 3825);
DISPLAY 1.021277 (1200 3825);
PAINT ORANGE (1200 3825);
DISPLAY INVISIBLE (1200 3825);
FORCEPROP 2 LAST CDS_LIB mstr_discrete
J 2
(1200 3675);
DISPLAY 1.340426 (1200 3675);
PAINT ORANGE (1200 3675);
DISPLAY INVISIBLE (1200 3675);
FORCEPROP 2 LAST CDS_LOCATION C8E6
J 1
(1200 3725);
DISPLAY 0.617021 (1200 3725);
PAINT AQUA (1200 3725);
DISPLAY INVISIBLE (1200 3725);
FORCEPROP 2 LAST ROOM P5V_STBY_VR
J 0
(1200 3775);
DISPLAY 1.021277 (1200 3775);
PAINT ORANGE (1200 3775);
DISPLAY INVISIBLE (1200 3775);
FORCEADD CAP..1
(1500 4400);
FORCEPROP 1 LAST PACK_TYPE 0402LF
J 0
(1550 4200);
DISPLAY 0.617021 (1550 4200);
PAINT SKYBLUE (1550 4200);
FORCEPROP 1 LAST MATERIAL X7R
J 0
(1550 4250);
DISPLAY 0.617021 (1550 4250);
PAINT SKYBLUE (1550 4250);
FORCEPROP 1 LAST TOLERANCE 10%
J 0
(1550 4300);
DISPLAY 0.617021 (1550 4300);
PAINT SKYBLUE (1550 4300);
FORCEPROP 1 LASTPIN (1500 4300) $PN 2
J 0
(1510 4280);
DISPLAY 0.617021 (1510 4280);
PAINT WHITE (1510 4280);
FORCEPROP 1 LAST PART_NUMBER A36096-046
R 1
J 0
(1450 4200);
DISPLAY 0.617021 (1450 4200);
PAINT BLUE (1450 4200);
FORCEPROP 1 LAST VALUE 1000PF
J 0
(1550 4400);
DISPLAY 0.617021 (1550 4400);
PAINT SKYBLUE (1550 4400);
FORCEPROP 1 LAST VOLTAGE 50V
J 0
(1550 4350);
DISPLAY 0.617021 (1550 4350);
PAINT SKYBLUE (1550 4350);
FORCEPROP 1 LAST LOCATION C7E10
J 0
(1550 4450);
DISPLAY 0.617021 (1550 4450);
PAINT AQUA (1550 4450);
FORCEPROP 1 LASTPIN (1500 4500) $PN 1
J 0
(1510 4480);
DISPLAY 0.617021 (1510 4480);
PAINT WHITE (1510 4480);
FORCEPROP 2 LAST SEC 1
J 0
(1550 4600);
DISPLAY 0.914894 (1550 4600);
PAINT MONO (1550 4600);
DISPLAY INVISIBLE (1550 4600);
FORCEPROP 2 LAST REUSE_ID 17
J 0
(1550 4600);
DISPLAY 1.361702 (1550 4600);
PAINT ORANGE (1550 4600);
DISPLAY INVISIBLE (1550 4600);
FORCEPROP 2 LAST SEC_TYPE 0402LF
J 0
(1550 4600);
DISPLAY 1.361702 (1550 4600);
PAINT ORANGE (1550 4600);
DISPLAY INVISIBLE (1550 4600);
FORCEPROP 2 LAST ROOM P5V_STBY_VR
J 0
(1550 4500);
DISPLAY 1.021277 (1550 4500);
PAINT ORANGE (1550 4500);
DISPLAY INVISIBLE (1550 4500);
FORCEPROP 1 LAST PATH I14
J 0
(1550 4550);
DISPLAY 0.978723 (1550 4550);
PAINT WHITE (1550 4550);
DISPLAY INVISIBLE (1550 4550);
FORCEPROP 2 LAST CDS_LOCATION C7E10
J 0
(1550 4450);
DISPLAY 0.617021 (1550 4450);
PAINT AQUA (1550 4450);
DISPLAY INVISIBLE (1550 4450);
FORCEPROP 2 LAST BOM_COST P5V_STBY_VR
J 0
(1550 4550);
DISPLAY 1.021277 (1550 4550);
PAINT ORANGE (1550 4550);
DISPLAY INVISIBLE (1550 4550);
FORCEPROP 2 LAST CDS_LIB mstr_discrete
J 0
(1500 4400);
DISPLAY 1.340426 (1500 4400);
PAINT ORANGE (1500 4400);
DISPLAY INVISIBLE (1500 4400);
FORCEADD GND..1
(1500 4150);
FORCEPROP 3 LASTPIN (1500 4200) SIG_NAME GND\g
J 0
(1510 4210);
DISPLAY 0.659574 (1510 4210);
PAINT MONO (1510 4210);
DISPLAY INVISIBLE (1510 4210);
FORCEPROP 1 LAST PATH I16
J 0
(1575 4150);
DISPLAY 0.872340 (1575 4150);
PAINT AQUA (1575 4150);
DISPLAY INVISIBLE (1575 4150);
FORCEPROP 1 LAST SIZE 1B
J 0
(1575 4100);
DISPLAY 1.191489 (1575 4100);
PAINT GREEN (1575 4100);
DISPLAY INVISIBLE (1575 4100);
FORCEPROP 1 LAST VOLTAGE 0
J 0
(1500 4150);
DISPLAY 1.340426 (1500 4150);
PAINT SKYBLUE (1500 4150);
DISPLAY INVISIBLE (1500 4150);
FORCEPROP 2 LAST CDS_LIB mstr_symbols
J 0
(1500 4150);
DISPLAY 1.340426 (1500 4150);
PAINT MONO (1500 4150);
DISPLAY INVISIBLE (1500 4150);
FORCEPROP 1 LAST BODY_TYPE PLUMBING
J 0
(1455 4107);
DISPLAY 0.340426 (1455 4107);
PAINT GREEN (1455 4107);
DISPLAY INVISIBLE (1455 4107);
FORCEPROP 1 LAST HDL_POWER GND
J 0
(1500 4300);
DISPLAY 1.191489 (1500 4300);
PAINT GREEN (1500 4300);
DISPLAY INVISIBLE (1500 4300);
FORCEADD RES..2
(-825 2600);
FORCEPROP 1 LAST PART_NUMBER G21796-224
J 0
(-785 2475);
DISPLAY 0.617021 (-785 2475);
PAINT BLUE (-785 2475);
FORCEPROP 1 LAST VALUE 75K
J 0
(-780 2675);
DISPLAY 0.617021 (-780 2675);
PAINT SKYBLUE (-780 2675);
FORCEPROP 1 LAST TOLERANCE 1%
J 0
(-780 2625);
DISPLAY 0.617021 (-780 2625);
PAINT SKYBLUE (-780 2625);
FORCEPROP 1 LAST WATTAGE 1/16W
J 0
(-785 2575);
DISPLAY 0.617021 (-785 2575);
PAINT SKYBLUE (-785 2575);
FORCEPROP 1 LASTPIN (-825 2700) $PN 1
J 0
(-820 2662);
DISPLAY 0.617021 (-820 2662);
PAINT ORANGE (-820 2662);
FORCEPROP 1 LAST MATERIAL CHIP
J 0
(-785 2525);
DISPLAY 0.617021 (-785 2525);
PAINT SKYBLUE (-785 2525);
FORCEPROP 1 LASTPIN (-825 2500) $PN 2
J 0
(-820 2510);
DISPLAY 0.617021 (-820 2510);
PAINT ORANGE (-820 2510);
FORCEPROP 1 LAST LOCATION R7E14
J 0
(-780 2725);
DISPLAY 0.617021 (-780 2725);
PAINT AQUA (-780 2725);
FORCEPROP 1 LAST PACK_TYPE 0402
J 0
(-785 2425);
DISPLAY 0.617021 (-785 2425);
PAINT SKYBLUE (-785 2425);
FORCEPROP 2 LAST SEC_TYPE 0402
J 0
(-775 2825);
DISPLAY 1.021277 (-775 2825);
PAINT ORANGE (-775 2825);
DISPLAY INVISIBLE (-775 2825);
FORCEPROP 2 LAST SEC 1
J 0
(-775 2825);
DISPLAY 0.680851 (-775 2825);
PAINT MONO (-775 2825);
DISPLAY INVISIBLE (-775 2825);
FORCEPROP 2 LAST BOM_COST P5V_STBY_VR
J 0
(-775 2825);
DISPLAY 1.021277 (-775 2825);
PAINT ORANGE (-775 2825);
DISPLAY INVISIBLE (-775 2825);
FORCEPROP 2 LAST ROOM P5V_STBY_VR
J 0
(-775 2775);
DISPLAY 1.021277 (-775 2775);
PAINT ORANGE (-775 2775);
DISPLAY INVISIBLE (-775 2775);
FORCEPROP 2 LAST REUSE_ID 8
J 0
(-875 2800);
DISPLAY 1.361702 (-875 2800);
PAINT ORANGE (-875 2800);
DISPLAY INVISIBLE (-875 2800);
FORCEPROP 1 LAST PATH I18
J 0
(-775 2775);
DISPLAY 0.978723 (-775 2775);
PAINT WHITE (-775 2775);
DISPLAY INVISIBLE (-775 2775);
FORCEPROP 2 LAST CDS_LOCATION R7E14
J 0
(-780 2725);
DISPLAY 0.617021 (-780 2725);
PAINT AQUA (-780 2725);
DISPLAY INVISIBLE (-780 2725);
FORCEPROP 2 LAST CDS_LIB mstr_discrete
J 0
(-825 2600);
DISPLAY 1.340426 (-825 2600);
PAINT ORANGE (-825 2600);
DISPLAY INVISIBLE (-825 2600);
FORCEADD GND..1
(675 3125);
FORCEPROP 3 LASTPIN (675 3175) SIG_NAME GND\g
J 0
(685 3185);
DISPLAY 0.659574 (685 3185);
PAINT MONO (685 3185);
DISPLAY INVISIBLE (685 3185);
FORCEPROP 1 LAST PATH I19
J 0
(750 3125);
DISPLAY 0.872340 (750 3125);
PAINT AQUA (750 3125);
DISPLAY INVISIBLE (750 3125);
FORCEPROP 1 LAST SIZE 1B
J 0
(750 3075);
DISPLAY 1.191489 (750 3075);
PAINT GREEN (750 3075);
DISPLAY INVISIBLE (750 3075);
FORCEPROP 2 LAST CDS_LIB mstr_symbols
J 0
(675 3125);
DISPLAY 1.340426 (675 3125);
PAINT MONO (675 3125);
DISPLAY INVISIBLE (675 3125);
FORCEPROP 1 LAST VOLTAGE 0
J 0
(675 3125);
DISPLAY 1.340426 (675 3125);
PAINT SKYBLUE (675 3125);
DISPLAY INVISIBLE (675 3125);
FORCEPROP 1 LAST BODY_TYPE PLUMBING
J 0
(630 3082);
DISPLAY 0.340426 (630 3082);
PAINT GREEN (630 3082);
DISPLAY INVISIBLE (630 3082);
FORCEPROP 1 LAST HDL_POWER GND
J 0
(675 3275);
DISPLAY 1.191489 (675 3275);
PAINT GREEN (675 3275);
DISPLAY INVISIBLE (675 3275);
FORCEADD CAP..1
(-1400 3850);
FORCEPROP 1 LASTPIN (-1400 3750) $PN 2
J 0
(-1390 3730);
DISPLAY 0.617021 (-1390 3730);
PAINT WHITE (-1390 3730);
FORCEPROP 1 LASTPIN (-1400 3950) $PN 1
J 0
(-1390 3930);
DISPLAY 0.617021 (-1390 3930);
PAINT WHITE (-1390 3930);
FORCEPROP 1 LAST MATERIAL X6S
J 0
(-1350 3725);
DISPLAY 0.617021 (-1350 3725);
PAINT SKYBLUE (-1350 3725);
FORCEPROP 1 LAST PACK_TYPE 0402
J 0
(-1350 3675);
DISPLAY 0.617021 (-1350 3675);
PAINT SKYBLUE (-1350 3675);
FORCEPROP 1 LAST TOLERANCE 10%
J 0
(-1350 3775);
DISPLAY 0.617021 (-1350 3775);
PAINT SKYBLUE (-1350 3775);
FORCEPROP 1 LAST VOLTAGE 16V
J 0
(-1350 3825);
DISPLAY 0.617021 (-1350 3825);
PAINT SKYBLUE (-1350 3825);
FORCEPROP 1 LAST LOCATION C7E14
J 0
(-1350 3925);
DISPLAY 0.617021 (-1350 3925);
PAINT AQUA (-1350 3925);
FORCEPROP 1 LAST VALUE 1.0UF
J 0
(-1350 3875);
DISPLAY 0.617021 (-1350 3875);
PAINT SKYBLUE (-1350 3875);
FORCEPROP 1 LAST PART_NUMBER D97712-011
R 1
J 0
(-1450 3625);
DISPLAY 0.617021 (-1450 3625);
PAINT BLUE (-1450 3625);
FORCEPROP 2 LAST CDS_LOCATION C7E14
J 0
(-1350 3925);
DISPLAY 0.617021 (-1350 3925);
PAINT AQUA (-1350 3925);
DISPLAY INVISIBLE (-1350 3925);
FORCEPROP 2 LAST CDS_LIB mstr_discrete
J 0
(-1400 3850);
DISPLAY 1.340426 (-1400 3850);
PAINT ORANGE (-1400 3850);
DISPLAY INVISIBLE (-1400 3850);
FORCEPROP 2 LAST BOM_COST P5V_STBY_VR
J 0
(-1350 4025);
DISPLAY 1.021277 (-1350 4025);
PAINT ORANGE (-1350 4025);
DISPLAY INVISIBLE (-1350 4025);
FORCEPROP 2 LAST SEC 1
J 0
(-1350 4050);
DISPLAY 0.914894 (-1350 4050);
PAINT MONO (-1350 4050);
DISPLAY INVISIBLE (-1350 4050);
FORCEPROP 1 LAST PATH I30
J 0
(-1350 4000);
DISPLAY 0.978723 (-1350 4000);
PAINT WHITE (-1350 4000);
DISPLAY INVISIBLE (-1350 4000);
FORCEPROP 2 LAST ROOM P5V_STBY_VR
J 0
(-1350 3975);
DISPLAY 1.021277 (-1350 3975);
PAINT ORANGE (-1350 3975);
DISPLAY INVISIBLE (-1350 3975);
FORCEPROP 2 LAST SEC_TYPE 0402
J 0
(-1350 4050);
DISPLAY 1.361702 (-1350 4050);
PAINT ORANGE (-1350 4050);
DISPLAY INVISIBLE (-1350 4050);
FORCEPROP 0 LAST REUSE_ID 1
J 0
(-1350 4050);
DISPLAY 1.361702 (-1350 4050);
PAINT ORANGE (-1350 4050);
DISPLAY INVISIBLE (-1350 4050);
FORCEPROP 0 LAST FIN VR_1P2
J 0
(-1350 4150);
DISPLAY 1.340426 (-1350 4150);
PAINT ORANGE (-1350 4150);
DISPLAY INVISIBLE (-1350 4150);
FORCEADD GND..1
(-1400 3550);
FORCEPROP 3 LASTPIN (-1400 3600) SIG_NAME GND\g
J 0
(-1390 3610);
DISPLAY 0.659574 (-1390 3610);
PAINT MONO (-1390 3610);
DISPLAY INVISIBLE (-1390 3610);
FORCEPROP 1 LAST SIZE 1B
J 0
(-1325 3500);
DISPLAY 1.170213 (-1325 3500);
PAINT GREEN (-1325 3500);
DISPLAY INVISIBLE (-1325 3500);
FORCEPROP 1 LAST PATH I31
J 0
(-1325 3550);
DISPLAY 0.872340 (-1325 3550);
PAINT AQUA (-1325 3550);
DISPLAY INVISIBLE (-1325 3550);
FORCEPROP 2 LAST CDS_LIB mstr_symbols
J 0
(-1400 3550);
DISPLAY 1.340426 (-1400 3550);
PAINT MONO (-1400 3550);
DISPLAY INVISIBLE (-1400 3550);
FORCEPROP 1 LAST VOLTAGE 0
J 0
(-1400 3550);
DISPLAY 1.340426 (-1400 3550);
PAINT SKYBLUE (-1400 3550);
DISPLAY INVISIBLE (-1400 3550);
FORCEPROP 1 LAST BODY_TYPE PLUMBING
J 0
(-1445 3507);
DISPLAY 0.340426 (-1445 3507);
PAINT GREEN (-1445 3507);
DISPLAY INVISIBLE (-1445 3507);
FORCEPROP 1 LAST HDL_POWER GND
J 0
(-1400 3700);
DISPLAY 1.170213 (-1400 3700);
PAINT GREEN (-1400 3700);
DISPLAY INVISIBLE (-1400 3700);
FORCEADD GND..1
(-2000 2700);
FORCEPROP 3 LASTPIN (-2000 2750) SIG_NAME AGND_P5V_STBY\g
J 0
(-1990 2760);
DISPLAY 0.659574 (-1990 2760);
PAINT MONO (-1990 2760);
DISPLAY INVISIBLE (-1990 2760);
FORCEPROP 1 LAST HDL_POWER AGND_P5V_STBY
J 0
(-2275 2650);
DISPLAY 0.617021 (-2275 2650);
PAINT GREEN (-2275 2650);
FORCEPROP 1 LAST VOLTAGE 0
J 0
(-2000 2700);
DISPLAY 1.340426 (-2000 2700);
PAINT SKYBLUE (-2000 2700);
DISPLAY INVISIBLE (-2000 2700);
FORCEPROP 1 LAST SIZE 1B
J 0
(-1925 2650);
DISPLAY 1.170213 (-1925 2650);
PAINT AQUA (-1925 2650);
DISPLAY INVISIBLE (-1925 2650);
FORCEPROP 2 LAST CDS_LIB mstr_symbols
J 0
(-2000 2700);
PAINT MONO (-2000 2700);
DISPLAY INVISIBLE (-2000 2700);
FORCEPROP 1 LAST PATH I32
J 0
(-1925 2700);
DISPLAY 0.872340 (-1925 2700);
PAINT AQUA (-1925 2700);
DISPLAY INVISIBLE (-1925 2700);
FORCEPROP 1 LAST BODY_TYPE PLUMBING
J 0
(-2045 2657);
DISPLAY 0.340426 (-2045 2657);
PAINT GREEN (-2045 2657);
DISPLAY INVISIBLE (-2045 2657);
FORCEADD RES..2
(-1400 4200);
FORCEPROP 1 LAST VALUE 0.0
J 0
(-1355 4275);
DISPLAY 0.617021 (-1355 4275);
PAINT SKYBLUE (-1355 4275);
FORCEPROP 1 LAST PACK_TYPE 0402
J 0
(-1360 4075);
DISPLAY 0.617021 (-1360 4075);
PAINT SKYBLUE (-1360 4075);
FORCEPROP 1 LASTPIN (-1400 4100) $PN 2
J 0
(-1395 4110);
DISPLAY 0.617021 (-1395 4110);
PAINT WHITE (-1395 4110);
FORCEPROP 1 LASTPIN (-1400 4300) $PN 1
J 0
(-1395 4262);
DISPLAY 0.617021 (-1395 4262);
PAINT WHITE (-1395 4262);
FORCEPROP 1 LAST WATTAGE 1/16W
J 0
(-1360 4175);
DISPLAY 0.617021 (-1360 4175);
PAINT SKYBLUE (-1360 4175);
FORCEPROP 1 LAST TOLERANCE 5%
J 0
(-1355 4225);
DISPLAY 0.617021 (-1355 4225);
PAINT SKYBLUE (-1355 4225);
FORCEPROP 1 LAST LOCATION R7E17
J 0
(-1355 4325);
DISPLAY 0.617021 (-1355 4325);
PAINT AQUA (-1355 4325);
FORCEPROP 1 LAST PART_NUMBER G21497-005
R 1
J 0
(-1435 4050);
DISPLAY 0.617021 (-1435 4050);
PAINT BLUE (-1435 4050);
FORCEPROP 1 LAST MATERIAL CHIP
J 0
(-1360 4125);
DISPLAY 0.617021 (-1360 4125);
PAINT SKYBLUE (-1360 4125);
FORCEPROP 2 LAST CDS_LIB mstr_discrete
J 0
(-1400 4200);
DISPLAY 1.340426 (-1400 4200);
PAINT ORANGE (-1400 4200);
DISPLAY INVISIBLE (-1400 4200);
FORCEPROP 2 LAST CDS_LOCATION R7E17
J 0
(-1355 4325);
DISPLAY 0.617021 (-1355 4325);
PAINT AQUA (-1355 4325);
DISPLAY INVISIBLE (-1355 4325);
FORCEPROP 2 LAST SEC 1
J 0
(-1350 4425);
DISPLAY 0.914894 (-1350 4425);
PAINT MONO (-1350 4425);
DISPLAY INVISIBLE (-1350 4425);
FORCEPROP 2 LAST BOM_COST P5V_STBY_VR
J 0
(-1350 4425);
DISPLAY 1.021277 (-1350 4425);
PAINT ORANGE (-1350 4425);
DISPLAY INVISIBLE (-1350 4425);
FORCEPROP 1 LAST PATH I37
J 0
(-1350 4375);
DISPLAY 0.978723 (-1350 4375);
PAINT WHITE (-1350 4375);
DISPLAY INVISIBLE (-1350 4375);
FORCEPROP 2 LAST ROOM P5V_STBY_VR
J 0
(-1350 4375);
DISPLAY 1.021277 (-1350 4375);
PAINT ORANGE (-1350 4375);
DISPLAY INVISIBLE (-1350 4375);
FORCEPROP 2 LAST SEC_TYPE 0402
J 0
(-1350 4425);
DISPLAY 1.361702 (-1350 4425);
PAINT ORANGE (-1350 4425);
DISPLAY INVISIBLE (-1350 4425);
FORCEPROP 2 LAST $REUSE_ID 13
J 0
(-1350 4425);
DISPLAY 1.361702 (-1350 4425);
PAINT ORANGE (-1350 4425);
DISPLAY INVISIBLE (-1350 4425);
FORCEPROP 2 LAST NO_XNET_CONNECTION 1
J 0
(-1350 4425);
PAINT MONO (-1350 4425);
DISPLAY INVISIBLE (-1350 4425);
FORCEADD CAP..1
(-1750 4275);
FORCEPROP 1 LASTPIN (-1750 4375) $PN 1
J 0
(-1740 4355);
DISPLAY 0.617021 (-1740 4355);
PAINT WHITE (-1740 4355);
FORCEPROP 1 LAST PART_NUMBER D38464-005
R 1
J 0
(-1800 4100);
DISPLAY 0.617021 (-1800 4100);
PAINT BLUE (-1800 4100);
FORCEPROP 1 LASTPIN (-1750 4175) $PN 2
J 0
(-1740 4155);
DISPLAY 0.617021 (-1740 4155);
PAINT WHITE (-1740 4155);
FORCEPROP 1 LAST MATERIAL X6S
J 0
(-1700 4125);
DISPLAY 0.617021 (-1700 4125);
PAINT SKYBLUE (-1700 4125);
FORCEPROP 1 LAST PACK_TYPE 1206LF
J 0
(-1700 4075);
DISPLAY 0.617021 (-1700 4075);
PAINT SKYBLUE (-1700 4075);
FORCEPROP 1 LAST VOLTAGE 16V
J 0
(-1700 4225);
DISPLAY 0.617021 (-1700 4225);
PAINT SKYBLUE (-1700 4225);
FORCEPROP 1 LAST TOLERANCE 10%
J 0
(-1700 4175);
DISPLAY 0.617021 (-1700 4175);
PAINT SKYBLUE (-1700 4175);
FORCEPROP 1 LAST LOCATION C7E11
J 0
(-1700 4325);
DISPLAY 0.617021 (-1700 4325);
PAINT AQUA (-1700 4325);
FORCEPROP 1 LAST VALUE 22UF
J 0
(-1700 4275);
DISPLAY 0.617021 (-1700 4275);
PAINT SKYBLUE (-1700 4275);
FORCEPROP 2 LAST BOM_COST P5V_STBY_VR
J 0
(-1700 4425);
DISPLAY 1.021277 (-1700 4425);
PAINT ORANGE (-1700 4425);
DISPLAY INVISIBLE (-1700 4425);
FORCEPROP 2 LAST SEC_TYPE 1206LF
J 0
(-1700 4475);
DISPLAY 1.021277 (-1700 4475);
PAINT ORANGE (-1700 4475);
DISPLAY INVISIBLE (-1700 4475);
FORCEPROP 1 LAST PATH I39
J 0
(-1700 4425);
DISPLAY 0.978723 (-1700 4425);
PAINT WHITE (-1700 4425);
DISPLAY INVISIBLE (-1700 4425);
FORCEPROP 2 LAST SEC 1
J 0
(-1700 4475);
DISPLAY 0.680851 (-1700 4475);
PAINT MONO (-1700 4475);
DISPLAY INVISIBLE (-1700 4475);
FORCEPROP 2 LAST ROOM P5V_STBY_VR
J 0
(-1700 4375);
DISPLAY 1.021277 (-1700 4375);
PAINT ORANGE (-1700 4375);
DISPLAY INVISIBLE (-1700 4375);
FORCEPROP 2 LAST CDS_LIB mstr_discrete
J 0
(-1750 4275);
DISPLAY 1.340426 (-1750 4275);
PAINT ORANGE (-1750 4275);
DISPLAY INVISIBLE (-1750 4275);
FORCEPROP 2 LAST CDS_LOCATION C7E11
J 0
(-1700 4325);
DISPLAY 0.617021 (-1700 4325);
PAINT AQUA (-1700 4325);
DISPLAY INVISIBLE (-1700 4325);
FORCEADD GND..1
(3800 3450);
FORCEPROP 3 LASTPIN (3800 3500) SIG_NAME GND\g
J 0
(3810 3510);
DISPLAY 0.659574 (3810 3510);
PAINT MONO (3810 3510);
DISPLAY INVISIBLE (3810 3510);
FORCEPROP 1 LAST PATH I4
J 0
(3875 3450);
DISPLAY 0.872340 (3875 3450);
PAINT AQUA (3875 3450);
DISPLAY INVISIBLE (3875 3450);
FORCEPROP 2 LAST CDS_LIB mstr_symbols
J 0
(3800 3450);
DISPLAY 1.340426 (3800 3450);
PAINT MONO (3800 3450);
DISPLAY INVISIBLE (3800 3450);
FORCEPROP 1 LAST SIZE 1B
J 0
(3875 3400);
DISPLAY 1.170213 (3875 3400);
PAINT GREEN (3875 3400);
DISPLAY INVISIBLE (3875 3400);
FORCEPROP 1 LAST VOLTAGE 0
J 0
(3800 3450);
DISPLAY 1.340426 (3800 3450);
PAINT SKYBLUE (3800 3450);
DISPLAY INVISIBLE (3800 3450);
FORCEPROP 1 LAST BODY_TYPE PLUMBING
J 0
(3755 3407);
DISPLAY 0.340426 (3755 3407);
PAINT GREEN (3755 3407);
DISPLAY INVISIBLE (3755 3407);
FORCEPROP 1 LAST HDL_POWER GND
J 0
(3800 3600);
DISPLAY 1.170213 (3800 3600);
PAINT GREEN (3800 3600);
DISPLAY INVISIBLE (3800 3600);
FORCEADD GND..1
(-1750 4050);
FORCEPROP 3 LASTPIN (-1750 4100) SIG_NAME GND\g
J 0
(-1740 4110);
DISPLAY 0.659574 (-1740 4110);
PAINT MONO (-1740 4110);
DISPLAY INVISIBLE (-1740 4110);
FORCEPROP 2 LAST CDS_LIB mstr_symbols
J 0
(-1750 4050);
DISPLAY 1.340426 (-1750 4050);
PAINT MONO (-1750 4050);
DISPLAY INVISIBLE (-1750 4050);
FORCEPROP 1 LAST VOLTAGE 0
J 0
(-1750 4050);
DISPLAY 1.340426 (-1750 4050);
PAINT SKYBLUE (-1750 4050);
DISPLAY INVISIBLE (-1750 4050);
FORCEPROP 1 LAST SIZE 1B
J 0
(-1675 4000);
DISPLAY 1.170213 (-1675 4000);
PAINT GREEN (-1675 4000);
DISPLAY INVISIBLE (-1675 4000);
FORCEPROP 1 LAST PATH I40
J 0
(-1675 4050);
DISPLAY 0.872340 (-1675 4050);
PAINT AQUA (-1675 4050);
DISPLAY INVISIBLE (-1675 4050);
FORCEPROP 1 LAST BODY_TYPE PLUMBING
J 0
(-1795 4007);
DISPLAY 0.340426 (-1795 4007);
PAINT GREEN (-1795 4007);
DISPLAY INVISIBLE (-1795 4007);
FORCEPROP 1 LAST HDL_POWER GND
J 0
(-1750 4200);
DISPLAY 1.170213 (-1750 4200);
PAINT GREEN (-1750 4200);
DISPLAY INVISIBLE (-1750 4200);
FORCEADD CAP..1
R 2
(-2000 3075);
FORCEPROP 1 LAST LOCATION C8E13
J 2
(-2075 3125);
DISPLAY 0.617021 (-2075 3125);
PAINT AQUA (-2075 3125);
FORCEPROP 1 LAST VALUE 1000PF
J 2
(-2050 3075);
DISPLAY 0.617021 (-2050 3075);
PAINT SKYBLUE (-2050 3075);
FORCEPROP 1 LASTPIN (-2000 3175) $PN 1
J 2
(-2010 3155);
DISPLAY 0.617021 (-2010 3155);
PAINT WHITE (-2010 3155);
FORCEPROP 1 LASTPIN (-2000 2975) $PN 2
J 2
(-2010 2955);
DISPLAY 0.617021 (-2010 2955);
PAINT WHITE (-2010 2955);
FORCEPROP 1 LAST VOLTAGE 50V
J 2
(-2050 3025);
DISPLAY 0.617021 (-2050 3025);
PAINT SKYBLUE (-2050 3025);
FORCEPROP 1 LAST TOLERANCE 10%
J 2
(-2050 2975);
DISPLAY 0.617021 (-2050 2975);
PAINT SKYBLUE (-2050 2975);
FORCEPROP 1 LAST PACK_TYPE 0402LF
J 2
(-2050 2875);
DISPLAY 0.617021 (-2050 2875);
PAINT SKYBLUE (-2050 2875);
FORCEPROP 1 LAST MATERIAL EMPTY
J 2
(-2050 2925);
DISPLAY 0.617021 (-2050 2925);
PAINT RED (-2050 2925);
FORCEPROP 1 LAST PART_NUMBER A36096-046
R 1
J 2
(-1925 3250);
DISPLAY 0.617021 (-1925 3250);
PAINT BLUE (-1925 3250);
FORCEPROP 2 LAST CDS_LIB mstr_discrete
J 0
(-2000 3075);
DISPLAY 1.340426 (-2000 3075);
PAINT ORANGE (-2000 3075);
DISPLAY INVISIBLE (-2000 3075);
FORCEPROP 0 LAST FIN VR_1P2
J 2
(-2050 3375);
DISPLAY 1.340426 (-2050 3375);
PAINT ORANGE (-2050 3375);
DISPLAY INVISIBLE (-2050 3375);
FORCEPROP 2 LAST SEC_TYPE 0402LF
J 0
(-2050 3275);
DISPLAY 1.361702 (-2050 3275);
PAINT ORANGE (-2050 3275);
DISPLAY INVISIBLE (-2050 3275);
FORCEPROP 0 LAST REUSE_ID 1
J 2
(-2050 3275);
DISPLAY 1.361702 (-2050 3275);
PAINT ORANGE (-2050 3275);
DISPLAY INVISIBLE (-2050 3275);
FORCEPROP 2 LAST BOM_COST P5V_STBY_VR
J 0
(-2075 3225);
DISPLAY 1.021277 (-2075 3225);
PAINT ORANGE (-2075 3225);
DISPLAY INVISIBLE (-2075 3225);
FORCEPROP 2 LAST SEC 1
J 0
(-2050 3275);
DISPLAY 0.914894 (-2050 3275);
PAINT MONO (-2050 3275);
DISPLAY INVISIBLE (-2050 3275);
FORCEPROP 2 LAST CDS_LOCATION C8E13
J 2
(-2075 3125);
DISPLAY 0.617021 (-2075 3125);
PAINT AQUA (-2075 3125);
DISPLAY INVISIBLE (-2075 3125);
FORCEPROP 1 LAST PATH I41
J 2
(-2050 3225);
DISPLAY 0.978723 (-2050 3225);
PAINT WHITE (-2050 3225);
DISPLAY INVISIBLE (-2050 3225);
FORCEPROP 2 LAST ROOM P5V_STBY_VR
J 0
(-2075 3175);
DISPLAY 1.021277 (-2075 3175);
PAINT ORANGE (-2075 3175);
DISPLAY INVISIBLE (-2075 3175);
FORCEADD OFFPAGE..1
(-3300 3475);
FORCEPROP 2 LAST $XR2 248 
J 0
(-3552 3439);
DISPLAY 0.638298 (-3552 3439);
PAINT MONO (-3552 3439);
FORCEPROP 2 LAST $XR1 181 
J 0
(-3672 3475);
DISPLAY 0.638298 (-3672 3475);
PAINT MONO (-3672 3475);
FORCEPROP 2 LAST $XR0 196 
J 0
(-3552 3475);
DISPLAY 0.638298 (-3552 3475);
PAINT MONO (-3552 3475);
FORCEPROP 2 LAST CDS_LIB mstr_standard
J 0
(-3300 3475);
PAINT MONO (-3300 3475);
DISPLAY INVISIBLE (-3300 3475);
FORCEPROP 2 LAST PATH I48
J 0
(-3725 3525);
DISPLAY 1.021277 (-3725 3525);
PAINT ORANGE (-3725 3525);
DISPLAY INVISIBLE (-3725 3525);
FORCEPROP 1 LAST OFFPAGE TRUE
J 0
(-2975 3350);
DISPLAY 1.170213 (-2975 3350);
PAINT GREEN (-2975 3350);
DISPLAY INVISIBLE (-2975 3350);
FORCEPROP 1 LAST COMMENT_BODY TRUE
J 0
(-3175 3375);
DISPLAY 1.170213 (-3175 3375);
PAINT GREEN (-3175 3375);
DISPLAY INVISIBLE (-3175 3375);
FORCEADD RES..2
(1750 3425);
FORCEPROP 1 LAST WATTAGE 1/16W
J 0
(1790 3375);
DISPLAY 0.617021 (1790 3375);
PAINT SKYBLUE (1790 3375);
FORCEPROP 1 LAST MATERIAL CHIP
J 0
(1790 3300);
DISPLAY 0.617021 (1790 3300);
PAINT SKYBLUE (1790 3300);
FORCEPROP 1 LAST PACK_TYPE 0402
J 0
(1790 3250);
DISPLAY 0.617021 (1790 3250);
PAINT SKYBLUE (1790 3250);
FORCEPROP 1 LAST LOCATION R7F1
J 0
(1795 3550);
DISPLAY 0.617021 (1795 3550);
PAINT AQUA (1795 3550);
FORCEPROP 1 LAST VALUE 10.0K
J 0
(1795 3475);
DISPLAY 0.617021 (1795 3475);
PAINT SKYBLUE (1795 3475);
FORCEPROP 1 LAST PART_NUMBER G21796-016
R 1
J 0
(1715 3200);
DISPLAY 0.617021 (1715 3200);
PAINT BLUE (1715 3200);
FORCEPROP 1 LAST TOLERANCE 1%
J 0
(1795 3425);
DISPLAY 0.617021 (1795 3425);
PAINT SKYBLUE (1795 3425);
FORCEPROP 1 LASTPIN (1750 3525) $PN 1
J 0
(1755 3487);
DISPLAY 0.617021 (1755 3487);
PAINT WHITE (1755 3487);
FORCEPROP 1 LASTPIN (1750 3325) $PN 2
J 0
(1755 3335);
DISPLAY 0.617021 (1755 3335);
PAINT WHITE (1755 3335);
FORCEPROP 2 LAST BOM_COST P5V_STBY_VR
J 0
(1800 3650);
DISPLAY 1.021277 (1800 3650);
PAINT ORANGE (1800 3650);
DISPLAY INVISIBLE (1800 3650);
FORCEPROP 2 LAST SPOF TRUE
J 0
(1795 3605);
DISPLAY 1.340426 (1795 3605);
PAINT MONO (1795 3605);
DISPLAY INVISIBLE (1795 3605);
FORCEPROP 1 LAST PATH I50
J 0
(1800 3600);
DISPLAY 0.978723 (1800 3600);
PAINT WHITE (1800 3600);
DISPLAY INVISIBLE (1800 3600);
FORCEPROP 2 LAST SEC 1
J 0
(1800 3650);
DISPLAY 0.914894 (1800 3650);
PAINT MONO (1800 3650);
DISPLAY INVISIBLE (1800 3650);
FORCEPROP 2 LAST ROOM P5V_STBY_VR
J 0
(1800 3600);
DISPLAY 1.021277 (1800 3600);
PAINT ORANGE (1800 3600);
DISPLAY INVISIBLE (1800 3600);
FORCEPROP 2 LAST REUSE_ID 9
J 0
(1800 3650);
DISPLAY 1.361702 (1800 3650);
PAINT ORANGE (1800 3650);
DISPLAY INVISIBLE (1800 3650);
FORCEPROP 2 LAST SEC_TYPE 0402
J 0
(1800 3650);
DISPLAY 1.361702 (1800 3650);
PAINT ORANGE (1800 3650);
DISPLAY INVISIBLE (1800 3650);
FORCEPROP 2 LAST CDS_LOCATION R7F1
J 0
(1795 3550);
DISPLAY 0.617021 (1795 3550);
PAINT AQUA (1795 3550);
DISPLAY INVISIBLE (1795 3550);
FORCEPROP 2 LAST CDS_LIB mstr_discrete
J 0
(1750 3425);
DISPLAY 1.340426 (1750 3425);
PAINT ORANGE (1750 3425);
DISPLAY INVISIBLE (1750 3425);
FORCEADD RES..2
(1750 2900);
FORCEPROP 1 LAST LOCATION R7E16
J 0
(1795 3000);
DISPLAY 0.617021 (1795 3000);
PAINT AQUA (1795 3000);
FORCEPROP 1 LAST PART_NUMBER G21796-095
R 1
J 0
(1715 2725);
DISPLAY 0.617021 (1715 2725);
PAINT BLUE (1715 2725);
FORCEPROP 1 LAST VALUE 1.37K
J 0
(1795 2950);
DISPLAY 0.617021 (1795 2950);
PAINT SKYBLUE (1795 2950);
FORCEPROP 1 LAST TOLERANCE 1%
J 0
(1795 2900);
DISPLAY 0.617021 (1795 2900);
PAINT SKYBLUE (1795 2900);
FORCEPROP 1 LAST PACK_TYPE 0402
J 0
(1790 2725);
DISPLAY 0.617021 (1790 2725);
PAINT SKYBLUE (1790 2725);
FORCEPROP 1 LAST MATERIAL CHIP
J 0
(1790 2775);
DISPLAY 0.617021 (1790 2775);
PAINT SKYBLUE (1790 2775);
FORCEPROP 1 LAST WATTAGE 1/16W
J 0
(1790 2850);
DISPLAY 0.617021 (1790 2850);
PAINT SKYBLUE (1790 2850);
FORCEPROP 1 LASTPIN (1750 3000) $PN 1
J 0
(1755 2962);
DISPLAY 0.617021 (1755 2962);
PAINT WHITE (1755 2962);
FORCEPROP 1 LASTPIN (1750 2800) $PN 2
J 0
(1755 2810);
DISPLAY 0.617021 (1755 2810);
PAINT WHITE (1755 2810);
FORCEPROP 2 LAST SEC_TYPE 0402
J 0
(1800 3125);
DISPLAY 1.361702 (1800 3125);
PAINT ORANGE (1800 3125);
DISPLAY INVISIBLE (1800 3125);
FORCEPROP 2 LAST BOM_COST P5V_STBY_VR
J 0
(1800 3100);
DISPLAY 1.021277 (1800 3100);
PAINT ORANGE (1800 3100);
DISPLAY INVISIBLE (1800 3100);
FORCEPROP 0 LAST SPOF TRUE
J 0
(1800 3100);
DISPLAY 1.021277 (1800 3100);
PAINT ORANGE (1800 3100);
DISPLAY INVISIBLE (1800 3100);
FORCEPROP 2 LAST REUSE_ID 7
J 0
(1800 3125);
DISPLAY 1.361702 (1800 3125);
PAINT ORANGE (1800 3125);
DISPLAY INVISIBLE (1800 3125);
FORCEPROP 2 LAST SEC 1
J 0
(1800 3125);
DISPLAY 0.914894 (1800 3125);
PAINT MONO (1800 3125);
DISPLAY INVISIBLE (1800 3125);
FORCEPROP 1 LAST PATH I51
J 0
(1800 3075);
DISPLAY 0.978723 (1800 3075);
PAINT WHITE (1800 3075);
DISPLAY INVISIBLE (1800 3075);
FORCEPROP 2 LAST ROOM P5V_STBY_VR
J 0
(1800 3050);
DISPLAY 1.021277 (1800 3050);
PAINT ORANGE (1800 3050);
DISPLAY INVISIBLE (1800 3050);
FORCEPROP 2 LAST CDS_LOCATION R7E16
J 0
(1795 3000);
DISPLAY 0.617021 (1795 3000);
PAINT AQUA (1795 3000);
DISPLAY INVISIBLE (1795 3000);
FORCEPROP 2 LAST CDS_LIB mstr_discrete
J 0
(1750 2900);
DISPLAY 1.340426 (1750 2900);
PAINT ORANGE (1750 2900);
DISPLAY INVISIBLE (1750 2900);
FORCEADD GND..1
(1750 2625);
FORCEPROP 3 LASTPIN (1750 2675) SIG_NAME AGND_P5V_STBY\g
J 0
(1760 2685);
DISPLAY 0.659574 (1760 2685);
PAINT MONO (1760 2685);
DISPLAY INVISIBLE (1760 2685);
FORCEPROP 1 LAST HDL_POWER AGND_P5V_STBY
J 0
(1600 2575);
DISPLAY 0.617021 (1600 2575);
PAINT GREEN (1600 2575);
FORCEPROP 1 LAST SIZE 1B
J 0
(1825 2575);
DISPLAY 1.170213 (1825 2575);
PAINT AQUA (1825 2575);
DISPLAY INVISIBLE (1825 2575);
FORCEPROP 1 LAST PATH I52
J 0
(1825 2625);
DISPLAY 0.872340 (1825 2625);
PAINT AQUA (1825 2625);
DISPLAY INVISIBLE (1825 2625);
FORCEPROP 1 LAST VOLTAGE 0
J 0
(1750 2625);
DISPLAY 1.340426 (1750 2625);
PAINT SKYBLUE (1750 2625);
DISPLAY INVISIBLE (1750 2625);
FORCEPROP 2 LAST CDS_LIB mstr_symbols
J 0
(1750 2625);
PAINT MONO (1750 2625);
DISPLAY INVISIBLE (1750 2625);
FORCEPROP 1 LAST BODY_TYPE PLUMBING
J 0
(1705 2582);
DISPLAY 0.340426 (1705 2582);
PAINT GREEN (1705 2582);
DISPLAY INVISIBLE (1705 2582);
FORCEADD CAP..2
(200 2575);
FORCEPROP 1 LASTPIN (300 2575) $PN 2
J 0
(285 2590);
DISPLAY 0.617021 (285 2590);
PAINT WHITE (285 2590);
FORCEPROP 1 LAST LOCATION C8E16
J 1
(200 2675);
DISPLAY 0.617021 (200 2675);
PAINT AQUA (200 2675);
FORCEPROP 1 LASTPIN (100 2575) $PN 1
J 0
(90 2590);
DISPLAY 0.617021 (90 2590);
PAINT WHITE (90 2590);
FORCEPROP 1 LAST VALUE 270PF
J 2
(175 2500);
DISPLAY 0.617021 (175 2500);
PAINT SKYBLUE (175 2500);
FORCEPROP 1 LAST PACK_TYPE 0402LF
J 1
(375 2450);
DISPLAY 0.617021 (375 2450);
PAINT SKYBLUE (375 2450);
FORCEPROP 1 LAST VOLTAGE 50V
J 0
(250 2500);
DISPLAY 0.617021 (250 2500);
PAINT SKYBLUE (250 2500);
FORCEPROP 1 LAST MATERIAL X7R
J 0
(325 2500);
DISPLAY 0.617021 (325 2500);
PAINT SKYBLUE (325 2500);
FORCEPROP 1 LAST PART_NUMBER A36096-065
J 1
(175 2450);
DISPLAY 0.617021 (175 2450);
PAINT BLUE (175 2450);
FORCEPROP 1 LAST TOLERANCE 10%
J 2
(75 2450);
DISPLAY 0.617021 (75 2450);
PAINT SKYBLUE (75 2450);
FORCEPROP 2 LAST SEC_TYPE 0402LF
J 0
(200 2825);
DISPLAY 1.361702 (200 2825);
PAINT ORANGE (200 2825);
DISPLAY INVISIBLE (200 2825);
FORCEPROP 2 LAST CDS_LIB mstr_discrete
J 0
(200 2575);
DISPLAY 1.340426 (200 2575);
PAINT ORANGE (200 2575);
DISPLAY INVISIBLE (200 2575);
FORCEPROP 2 LAST REUSE_ID 4
J 0
(200 2825);
DISPLAY 1.361702 (200 2825);
PAINT ORANGE (200 2825);
DISPLAY INVISIBLE (200 2825);
FORCEPROP 2 LAST BOM_COST P5V_STBY_VR
J 0
(200 2775);
DISPLAY 1.021277 (200 2775);
PAINT ORANGE (200 2775);
DISPLAY INVISIBLE (200 2775);
FORCEPROP 2 LAST SEC 1
J 0
(200 2825);
DISPLAY 0.914894 (200 2825);
PAINT MONO (200 2825);
DISPLAY INVISIBLE (200 2825);
FORCEPROP 2 LAST CDS_LOCATION C8E16
J 1
(200 2675);
DISPLAY 0.617021 (200 2675);
PAINT AQUA (200 2675);
DISPLAY INVISIBLE (200 2675);
FORCEPROP 1 LAST PATH I53
J 0
(200 2775);
DISPLAY 0.978723 (200 2775);
PAINT WHITE (200 2775);
DISPLAY INVISIBLE (200 2775);
FORCEPROP 2 LAST ROOM P5V_STBY_VR
J 0
(200 2725);
DISPLAY 1.021277 (200 2725);
PAINT ORANGE (200 2725);
DISPLAY INVISIBLE (200 2725);
FORCEADD RES..1
(-200 2200);
FORCEPROP 1 LAST TOLERANCE 1%
J 0
(-125 2125);
DISPLAY 0.617021 (-125 2125);
PAINT SKYBLUE (-125 2125);
FORCEPROP 1 LAST PACK_TYPE 0402
J 0
(-150 2075);
DISPLAY 0.617021 (-150 2075);
PAINT SKYBLUE (-150 2075);
FORCEPROP 1 LAST LOCATION R8E39
J 0
(-250 2250);
DISPLAY 0.617021 (-250 2250);
PAINT AQUA (-250 2250);
FORCEPROP 1 LASTPIN (-100 2200) $PN 2
J 0
(-138 2212);
DISPLAY 0.617021 (-138 2212);
PAINT WHITE (-138 2212);
FORCEPROP 1 LAST PART_NUMBER G21796-254
J 0
(-400 2075);
DISPLAY 0.617021 (-400 2075);
PAINT BLUE (-400 2075);
FORCEPROP 1 LAST VALUE 24.9K
J 2
(-200 2125);
DISPLAY 0.617021 (-200 2125);
PAINT SKYBLUE (-200 2125);
FORCEPROP 1 LASTPIN (-300 2200) $PN 1
J 0
(-288 2212);
DISPLAY 0.617021 (-288 2212);
PAINT WHITE (-288 2212);
FORCEPROP 1 LAST MATERIAL CHIP
J 0
(-200 2025);
DISPLAY 0.617021 (-200 2025);
PAINT SKYBLUE (-200 2025);
FORCEPROP 1 LAST WATTAGE 1/16W
J 2
(-225 2025);
DISPLAY 0.617021 (-225 2025);
PAINT SKYBLUE (-225 2025);
FORCEPROP 1 LAST PATH I54
J 0
(-250 2350);
DISPLAY 0.978723 (-250 2350);
PAINT WHITE (-250 2350);
DISPLAY INVISIBLE (-250 2350);
FORCEPROP 2 LAST BOM_COST P5V_STBY_VR
J 0
(-250 2350);
DISPLAY 1.021277 (-250 2350);
PAINT ORANGE (-250 2350);
DISPLAY INVISIBLE (-250 2350);
FORCEPROP 2 LAST SEC 1
J 0
(-250 2400);
DISPLAY 0.914894 (-250 2400);
PAINT MONO (-250 2400);
DISPLAY INVISIBLE (-250 2400);
FORCEPROP 2 LAST SEC_TYPE 0402
J 0
(-250 2400);
DISPLAY 1.361702 (-250 2400);
PAINT ORANGE (-250 2400);
DISPLAY INVISIBLE (-250 2400);
FORCEPROP 2 LAST REUSE_ID 10
J 0
(-250 2400);
DISPLAY 1.361702 (-250 2400);
PAINT ORANGE (-250 2400);
DISPLAY INVISIBLE (-250 2400);
FORCEPROP 2 LAST ROOM P5V_STBY_VR
J 0
(-250 2300);
DISPLAY 1.021277 (-250 2300);
PAINT ORANGE (-250 2300);
DISPLAY INVISIBLE (-250 2300);
FORCEPROP 2 LAST CDS_LIB mstr_discrete
J 0
(-200 2200);
DISPLAY 1.340426 (-200 2200);
PAINT ORANGE (-200 2200);
DISPLAY INVISIBLE (-200 2200);
FORCEPROP 2 LAST CDS_LOCATION R8E39
J 0
(-250 2250);
DISPLAY 0.617021 (-250 2250);
PAINT AQUA (-250 2250);
DISPLAY INVISIBLE (-250 2250);
FORCEADD GND..1
(1925 1325);
FORCEPROP 3 LASTPIN (1925 1375) SIG_NAME AGND_P5V_STBY\g
J 0
(1935 1385);
DISPLAY 0.659574 (1935 1385);
PAINT MONO (1935 1385);
DISPLAY INVISIBLE (1935 1385);
FORCEPROP 1 LAST HDL_POWER AGND_P5V_STBY
J 0
(1725 1250);
DISPLAY 0.617021 (1725 1250);
PAINT GREEN (1725 1250);
FORCEPROP 1 LAST VOLTAGE 0
J 0
(1925 1325);
DISPLAY 1.340426 (1925 1325);
PAINT SKYBLUE (1925 1325);
DISPLAY INVISIBLE (1925 1325);
FORCEPROP 1 LAST SIZE 1B
J 0
(2000 1275);
DISPLAY 1.170213 (2000 1275);
PAINT AQUA (2000 1275);
DISPLAY INVISIBLE (2000 1275);
FORCEPROP 2 LAST CDS_LIB mstr_symbols
J 0
(1925 1325);
PAINT MONO (1925 1325);
DISPLAY INVISIBLE (1925 1325);
FORCEPROP 1 LAST PATH I55
J 0
(2000 1325);
DISPLAY 0.872340 (2000 1325);
PAINT AQUA (2000 1325);
DISPLAY INVISIBLE (2000 1325);
FORCEPROP 1 LAST BODY_TYPE PLUMBING
J 0
(1880 1282);
DISPLAY 0.340426 (1880 1282);
PAINT GREEN (1880 1282);
DISPLAY INVISIBLE (1880 1282);
FORCEADD CAP..2
(575 2200);
FORCEPROP 1 LAST LOCATION C8F1
J 1
(575 2300);
DISPLAY 0.617021 (575 2300);
PAINT AQUA (575 2300);
FORCEPROP 1 LASTPIN (675 2200) $PN 2
J 0
(660 2215);
DISPLAY 0.617021 (660 2215);
PAINT WHITE (660 2215);
FORCEPROP 1 LAST VOLTAGE 50V
J 0
(625 2125);
DISPLAY 0.617021 (625 2125);
PAINT SKYBLUE (625 2125);
FORCEPROP 1 LAST PART_NUMBER A36096-075
J 1
(550 2075);
DISPLAY 0.617021 (550 2075);
PAINT BLUE (550 2075);
FORCEPROP 1 LAST VALUE 2200PF
J 2
(575 2125);
DISPLAY 0.617021 (575 2125);
PAINT SKYBLUE (575 2125);
FORCEPROP 1 LASTPIN (475 2200) $PN 1
J 0
(465 2215);
DISPLAY 0.617021 (465 2215);
PAINT WHITE (465 2215);
FORCEPROP 1 LAST TOLERANCE 10%
J 2
(500 2025);
DISPLAY 0.617021 (500 2025);
PAINT SKYBLUE (500 2025);
FORCEPROP 1 LAST MATERIAL X7R
J 0
(575 2025);
DISPLAY 0.617021 (575 2025);
PAINT SKYBLUE (575 2025);
FORCEPROP 1 LAST PACK_TYPE 0402LF
J 1
(500 1975);
DISPLAY 0.617021 (500 1975);
PAINT SKYBLUE (500 1975);
FORCEPROP 2 LAST ROOM P5V_STBY_VR
J 0
(575 2350);
DISPLAY 1.021277 (575 2350);
PAINT ORANGE (575 2350);
DISPLAY INVISIBLE (575 2350);
FORCEPROP 1 LAST PATH I57
J 0
(575 2400);
DISPLAY 0.978723 (575 2400);
PAINT WHITE (575 2400);
DISPLAY INVISIBLE (575 2400);
FORCEPROP 2 LAST SEC 1
J 0
(575 2450);
DISPLAY 0.914894 (575 2450);
PAINT MONO (575 2450);
DISPLAY INVISIBLE (575 2450);
FORCEPROP 2 LAST BOM_COST P5V_STBY_VR
J 0
(575 2400);
DISPLAY 1.021277 (575 2400);
PAINT ORANGE (575 2400);
DISPLAY INVISIBLE (575 2400);
FORCEPROP 2 LAST REUSE_ID 5
J 0
(575 2450);
DISPLAY 1.361702 (575 2450);
PAINT ORANGE (575 2450);
DISPLAY INVISIBLE (575 2450);
FORCEPROP 2 LAST SEC_TYPE 0402LF
J 0
(575 2450);
DISPLAY 1.361702 (575 2450);
PAINT ORANGE (575 2450);
DISPLAY INVISIBLE (575 2450);
FORCEPROP 2 LAST CDS_LOCATION C8F1
J 1
(575 2300);
DISPLAY 0.617021 (575 2300);
PAINT AQUA (575 2300);
DISPLAY INVISIBLE (575 2300);
FORCEPROP 2 LAST CDS_LIB mstr_discrete
J 0
(575 2200);
DISPLAY 1.340426 (575 2200);
PAINT ORANGE (575 2200);
DISPLAY INVISIBLE (575 2200);
FORCEADD RES..1
(1575 1550);
FORCEPROP 1 LASTPIN (1675 1550) $PN 2
J 0
(1637 1562);
DISPLAY 0.617021 (1637 1562);
PAINT WHITE (1637 1562);
FORCEPROP 1 LAST TOLERANCE 5%
J 0
(1575 1450);
DISPLAY 0.617021 (1575 1450);
PAINT SKYBLUE (1575 1450);
FORCEPROP 1 LAST PACK_TYPE 0402
J 0
(1750 1450);
DISPLAY 0.617021 (1750 1450);
PAINT SKYBLUE (1750 1450);
FORCEPROP 1 LAST MATERIAL CHIP
J 0
(1725 1400);
DISPLAY 0.617021 (1725 1400);
PAINT SKYBLUE (1725 1400);
FORCEPROP 1 LAST LOCATION R7E13
J 0
(1525 1600);
DISPLAY 0.617021 (1525 1600);
PAINT AQUA (1525 1600);
FORCEPROP 1 LAST PART_NUMBER G21497-005
J 0
(1525 1650);
DISPLAY 0.617021 (1525 1650);
PAINT BLUE (1525 1650);
FORCEPROP 1 LAST VALUE 0.0
J 2
(1550 1450);
DISPLAY 0.617021 (1550 1450);
PAINT SKYBLUE (1550 1450);
FORCEPROP 1 LAST WATTAGE 1/16W
J 2
(1675 1400);
DISPLAY 0.617021 (1675 1400);
PAINT SKYBLUE (1675 1400);
FORCEPROP 1 LASTPIN (1475 1550) $PN 1
J 0
(1487 1562);
DISPLAY 0.617021 (1487 1562);
PAINT WHITE (1487 1562);
FORCEPROP 2 LAST CDS_LIB mstr_discrete
J 0
(1575 1550);
PAINT MONO (1575 1550);
DISPLAY INVISIBLE (1575 1550);
FORCEPROP 2 LAST SPOF TRUE
J 0
(1620 1730);
DISPLAY 1.340426 (1620 1730);
PAINT MONO (1620 1730);
DISPLAY INVISIBLE (1620 1730);
FORCEPROP 2 LAST $REUSE_ID 13
J 0
(1625 1775);
DISPLAY 1.361702 (1625 1775);
PAINT ORANGE (1625 1775);
DISPLAY INVISIBLE (1625 1775);
FORCEPROP 2 LAST SEC_TYPE 0402
J 0
(1525 1750);
DISPLAY 1.021277 (1525 1750);
PAINT ORANGE (1525 1750);
DISPLAY INVISIBLE (1525 1750);
FORCEPROP 2 LAST BOM_COST P5V_STBY_VR
J 0
(1525 1750);
DISPLAY 1.021277 (1525 1750);
PAINT ORANGE (1525 1750);
DISPLAY INVISIBLE (1525 1750);
FORCEPROP 2 LAST SEC 1
J 0
(1525 1750);
DISPLAY 0.914894 (1525 1750);
PAINT MONO (1525 1750);
DISPLAY INVISIBLE (1525 1750);
FORCEPROP 2 LAST CDS_LOCATION R7E13
J 0
(1525 1600);
DISPLAY 0.617021 (1525 1600);
PAINT AQUA (1525 1600);
DISPLAY INVISIBLE (1525 1600);
FORCEPROP 1 LAST PATH I58
J 0
(1525 1700);
DISPLAY 0.978723 (1525 1700);
PAINT WHITE (1525 1700);
DISPLAY INVISIBLE (1525 1700);
FORCEPROP 2 LAST ROOM P5V_STBY_VR
J 0
(1525 1700);
DISPLAY 1.021277 (1525 1700);
PAINT ORANGE (1525 1700);
DISPLAY INVISIBLE (1525 1700);
FORCEADD GND..1
(1350 1325);
FORCEPROP 3 LASTPIN (1350 1375) SIG_NAME GND\g
J 0
(1360 1385);
DISPLAY 0.659574 (1360 1385);
PAINT MONO (1360 1385);
DISPLAY INVISIBLE (1360 1385);
FORCEPROP 1 LAST PATH I59
J 0
(1425 1325);
DISPLAY 0.872340 (1425 1325);
PAINT AQUA (1425 1325);
DISPLAY INVISIBLE (1425 1325);
FORCEPROP 1 LAST SIZE 1B
J 0
(1425 1275);
DISPLAY 1.170213 (1425 1275);
PAINT AQUA (1425 1275);
DISPLAY INVISIBLE (1425 1275);
FORCEPROP 2 LAST CDS_LIB mstr_symbols
J 0
(1350 1325);
DISPLAY 1.340426 (1350 1325);
PAINT MONO (1350 1325);
DISPLAY INVISIBLE (1350 1325);
FORCEPROP 1 LAST VOLTAGE 0
J 0
(1350 1325);
DISPLAY 1.340426 (1350 1325);
PAINT SKYBLUE (1350 1325);
DISPLAY INVISIBLE (1350 1325);
FORCEPROP 1 LAST BODY_TYPE PLUMBING
J 0
(1305 1282);
DISPLAY 0.340426 (1305 1282);
PAINT GREEN (1305 1282);
DISPLAY INVISIBLE (1305 1282);
FORCEPROP 1 LAST HDL_POWER GND
J 0
(1350 1475);
DISPLAY 1.170213 (1350 1475);
PAINT GREEN (1350 1475);
DISPLAY INVISIBLE (1350 1475);
FORCEADD CAP..1
R 2
(-1025 3000);
FORCEPROP 1 LAST VOLTAGE 16V
J 2
(-1075 3000);
DISPLAY 0.617021 (-1075 3000);
PAINT SKYBLUE (-1075 3000);
FORCEPROP 1 LAST PART_NUMBER A36096-073
R 1
J 2
(-950 3175);
DISPLAY 0.617021 (-950 3175);
PAINT BLUE (-950 3175);
FORCEPROP 1 LASTPIN (-1025 2900) $PN 2
J 2
(-1035 2880);
DISPLAY 0.617021 (-1035 2880);
PAINT WHITE (-1035 2880);
FORCEPROP 1 LAST PACK_TYPE 0402LF
J 2
(-1075 2825);
DISPLAY 0.617021 (-1075 2825);
PAINT SKYBLUE (-1075 2825);
FORCEPROP 1 LAST TOLERANCE 10%
J 2
(-1075 2950);
DISPLAY 0.617021 (-1075 2950);
PAINT SKYBLUE (-1075 2950);
FORCEPROP 1 LAST LOCATION C8E15
J 2
(-1075 3100);
DISPLAY 0.617021 (-1075 3100);
PAINT AQUA (-1075 3100);
FORCEPROP 1 LASTPIN (-1025 3100) $PN 1
J 2
(-1035 3080);
DISPLAY 0.617021 (-1035 3080);
PAINT WHITE (-1035 3080);
FORCEPROP 1 LAST MATERIAL X7R
J 2
(-1075 2900);
DISPLAY 0.617021 (-1075 2900);
PAINT SKYBLUE (-1075 2900);
FORCEPROP 1 LAST VALUE 0.022UF
J 2
(-1075 3050);
DISPLAY 0.617021 (-1075 3050);
PAINT SKYBLUE (-1075 3050);
FORCEPROP 1 LAST PATH I63
J 2
(-1075 3150);
DISPLAY 0.978723 (-1075 3150);
PAINT WHITE (-1075 3150);
DISPLAY INVISIBLE (-1075 3150);
FORCEPROP 2 LAST CDS_LIB mstr_discrete
J 0
(-1025 3000);
DISPLAY 1.340426 (-1025 3000);
PAINT ORANGE (-1025 3000);
DISPLAY INVISIBLE (-1025 3000);
FORCEPROP 2 LAST SEC_TYPE 0402LF
J 0
(-1075 3200);
DISPLAY 1.361702 (-1075 3200);
PAINT ORANGE (-1075 3200);
DISPLAY INVISIBLE (-1075 3200);
FORCEPROP 2 LAST REUSE_ID 16
J 0
(-1075 3200);
DISPLAY 1.361702 (-1075 3200);
PAINT ORANGE (-1075 3200);
DISPLAY INVISIBLE (-1075 3200);
FORCEPROP 2 LAST BOM_COST P5V_STBY_VR
J 0
(-1075 3200);
DISPLAY 1.021277 (-1075 3200);
PAINT ORANGE (-1075 3200);
DISPLAY INVISIBLE (-1075 3200);
FORCEPROP 2 LAST SEC 1
J 0
(-1075 3200);
DISPLAY 0.914894 (-1075 3200);
PAINT MONO (-1075 3200);
DISPLAY INVISIBLE (-1075 3200);
FORCEPROP 2 LAST CDS_LOCATION C8E15
J 2
(-1075 3100);
DISPLAY 0.617021 (-1075 3100);
PAINT AQUA (-1075 3100);
DISPLAY INVISIBLE (-1075 3100);
FORCEPROP 2 LAST ROOM P5V_STBY_VR
J 0
(-1075 3150);
DISPLAY 1.021277 (-1075 3150);
PAINT ORANGE (-1075 3150);
DISPLAY INVISIBLE (-1075 3150);
FORCEADD GND..1
(-925 2200);
FORCEPROP 3 LASTPIN (-925 2250) SIG_NAME AGND_P5V_STBY\g
J 0
(-915 2260);
DISPLAY 0.659574 (-915 2260);
PAINT MONO (-915 2260);
DISPLAY INVISIBLE (-915 2260);
FORCEPROP 1 LAST HDL_POWER AGND_P5V_STBY
J 0
(-1100 2150);
DISPLAY 0.617021 (-1100 2150);
PAINT GREEN (-1100 2150);
FORCEPROP 1 LAST VOLTAGE 0
J 0
(-925 2200);
DISPLAY 1.340426 (-925 2200);
PAINT SKYBLUE (-925 2200);
DISPLAY INVISIBLE (-925 2200);
FORCEPROP 2 LAST CDS_LIB mstr_symbols
J 0
(-925 2200);
PAINT MONO (-925 2200);
DISPLAY INVISIBLE (-925 2200);
FORCEPROP 1 LAST SIZE 1B
J 0
(-850 2150);
DISPLAY 1.170213 (-850 2150);
PAINT AQUA (-850 2150);
DISPLAY INVISIBLE (-850 2150);
FORCEPROP 1 LAST PATH I64
J 0
(-850 2200);
DISPLAY 0.872340 (-850 2200);
PAINT AQUA (-850 2200);
DISPLAY INVISIBLE (-850 2200);
FORCEPROP 1 LAST BODY_TYPE PLUMBING
J 0
(-970 2157);
DISPLAY 0.340426 (-970 2157);
PAINT GREEN (-970 2157);
DISPLAY INVISIBLE (-970 2157);
FORCEADD P5V_STBY..1
(3800 4250);
FORCEPROP 3 LASTPIN (3800 4200) SIG_NAME P5V_STBY\g
J 0
(3810 4210);
DISPLAY 0.659574 (3810 4210);
PAINT MONO (3810 4210);
DISPLAY INVISIBLE (3810 4210);
FORCEPROP 1 LAST PATH I69
J 0
(3845 4252);
DISPLAY 0.340426 (3845 4252);
PAINT GREEN (3845 4252);
DISPLAY INVISIBLE (3845 4252);
FORCEPROP 1 LAST VOLTAGE +5
J 0
(4000 4400);
DISPLAY 1.021277 (4000 4400);
PAINT SKYBLUE (4000 4400);
DISPLAY INVISIBLE (4000 4400);
FORCEPROP 2 LAST CDS_LIB mstr_symbols
J 0
(3800 4250);
PAINT ORANGE (3800 4250);
DISPLAY INVISIBLE (3800 4250);
FORCEPROP 1 LAST SIZE 1B
J 0
(3845 4272);
DISPLAY 0.340426 (3845 4272);
PAINT GREEN (3845 4272);
DISPLAY INVISIBLE (3845 4272);
FORCEPROP 1 LAST BODY_TYPE PLUMBING
J 0
(3755 4207);
DISPLAY 0.340426 (3755 4207);
PAINT GREEN (3755 4207);
DISPLAY INVISIBLE (3755 4207);
FORCEPROP 1 LAST HDL_POWER P5V_STBY
J 0
(3500 4125);
DISPLAY 0.872340 (3500 4125);
PAINT ORANGE (3500 4125);
DISPLAY INVISIBLE (3500 4125);
FORCEADD P12V_STBY..1
(-3525 4875);
FORCEPROP 3 LASTPIN (-3525 4825) SIG_NAME P12V_STBY\g
J 0
(-3515 4835);
DISPLAY 0.659574 (-3515 4835);
PAINT MONO (-3515 4835);
DISPLAY INVISIBLE (-3515 4835);
FORCEPROP 1 LAST PATH I71
J 0
(-3480 4877);
DISPLAY 0.340426 (-3480 4877);
PAINT GREEN (-3480 4877);
DISPLAY INVISIBLE (-3480 4877);
FORCEPROP 2 LAST CDS_LIB mstr_symbols
J 0
(-3525 4875);
PAINT ORANGE (-3525 4875);
DISPLAY INVISIBLE (-3525 4875);
FORCEPROP 1 LAST SIZE 1B
J 0
(-3480 4897);
DISPLAY 0.340426 (-3480 4897);
PAINT GREEN (-3480 4897);
DISPLAY INVISIBLE (-3480 4897);
FORCEPROP 1 LAST VOLTAGE 12.0V
J 0
(-3570 4832);
DISPLAY 0.340426 (-3570 4832);
PAINT SKYBLUE (-3570 4832);
DISPLAY INVISIBLE (-3570 4832);
FORCEPROP 1 LAST BODY_TYPE PLUMBING
J 0
(-3570 4832);
DISPLAY 0.340426 (-3570 4832);
PAINT GREEN (-3570 4832);
DISPLAY INVISIBLE (-3570 4832);
FORCEPROP 1 LAST HDL_POWER P12V_STBY
J 0
(-3825 4750);
DISPLAY 0.872340 (-3825 4750);
PAINT ORANGE (-3825 4750);
DISPLAY INVISIBLE (-3825 4750);
FORCEADD RES..1
(2075 3650);
FORCEPROP 0 LAST SPOF TRUE
J 0
(1875 3925);
DISPLAY 1.021277 (1875 3925);
PAINT ORANGE (1875 3925);
FORCEPROP 1 LAST MATERIAL CHIP
J 0
(2175 3525);
DISPLAY 0.638298 (2175 3525);
PAINT SKYBLUE (2175 3525);
FORCEPROP 1 LAST TOLERANCE 5%
J 0
(2025 3700);
DISPLAY 0.617021 (2025 3700);
PAINT SKYBLUE (2025 3700);
FORCEPROP 1 LAST VALUE 0.0
J 2
(1950 3700);
DISPLAY 0.617021 (1950 3700);
PAINT SKYBLUE (1950 3700);
FORCEPROP 1 LAST PART_NUMBER G21497-005
J 0
(1900 3775);
DISPLAY 0.617021 (1900 3775);
PAINT BLUE (1900 3775);
FORCEPROP 1 LAST PACK_TYPE 0402
J 0
(2025 3525);
DISPLAY 0.617021 (2025 3525);
PAINT SKYBLUE (2025 3525);
FORCEPROP 1 LASTPIN (1975 3650) $PN 1
J 0
(1987 3662);
DISPLAY 0.617021 (1987 3662);
PAINT ORANGE (1987 3662);
FORCEPROP 1 LASTPIN (2175 3650) $PN 2
J 0
(2137 3662);
DISPLAY 0.617021 (2137 3662);
PAINT ORANGE (2137 3662);
FORCEPROP 1 LAST WATTAGE 1/16W
J 2
(2150 3575);
DISPLAY 0.617021 (2150 3575);
PAINT SKYBLUE (2150 3575);
FORCEPROP 1 LAST LOCATION R8E37
J 0
(1875 3825);
DISPLAY 0.617021 (1875 3825);
PAINT AQUA (1875 3825);
FORCEPROP 2 LAST CDS_LIB mstr_discrete
J 0
(2075 3650);
PAINT ORANGE (2075 3650);
DISPLAY INVISIBLE (2075 3650);
FORCEPROP 2 LAST SEC_TYPE 0402
J 0
(2045 3870);
DISPLAY 1.021277 (2045 3870);
PAINT ORANGE (2045 3870);
DISPLAY INVISIBLE (2045 3870);
FORCEPROP 2 LAST BOM_COST P5V_STBY_VR
J 0
(1875 3925);
DISPLAY 1.021277 (1875 3925);
PAINT ORANGE (1875 3925);
DISPLAY INVISIBLE (1875 3925);
FORCEPROP 2 LAST SEC 1
J 0
(2045 3870);
DISPLAY 0.680851 (2045 3870);
PAINT MONO (2045 3870);
DISPLAY INVISIBLE (2045 3870);
FORCEPROP 2 LAST ROOM P5V_STBY_VR
J 0
(1875 3875);
DISPLAY 1.021277 (1875 3875);
PAINT ORANGE (1875 3875);
DISPLAY INVISIBLE (1875 3875);
FORCEPROP 2 LAST CDS_LOCATION R8E37
J 0
(1875 3825);
DISPLAY 0.617021 (1875 3825);
PAINT AQUA (1875 3825);
DISPLAY INVISIBLE (1875 3825);
FORCEPROP 1 LAST PATH I78
J 0
(2025 3800);
DISPLAY 0.978723 (2025 3800);
PAINT WHITE (2025 3800);
DISPLAY INVISIBLE (2025 3800);
FORCEADD FERRITE..1
(-3300 4675);
FORCEPROP 1 LAST PART_NUMBER 656554-051
J 0
(-3470 4615);
DISPLAY 0.617021 (-3470 4615);
PAINT BLUE (-3470 4615);
FORCEPROP 1 LASTPIN (-3400 4675) $PN 1
J 2
(-3365 4685);
DISPLAY 0.702128 (-3365 4685);
PAINT WHITE (-3365 4685);
FORCEPROP 1 LAST LOCATION FB7E1
J 0
(-3395 4730);
DISPLAY 0.617021 (-3395 4730);
PAINT AQUA (-3395 4730);
FORCEPROP 1 LASTPIN (-3200 4675) $PN 2
J 0
(-3220 4685);
DISPLAY 0.702128 (-3220 4685);
PAINT WHITE (-3220 4685);
FORCEPROP 1 LAST PACK_TYPE SM
J 0
(-3320 4575);
DISPLAY 0.617021 (-3320 4575);
PAINT SKYBLUE (-3320 4575);
FORCEPROP 1 LAST MATERIAL FB
J 0
(-3395 4575);
DISPLAY 0.617021 (-3395 4575);
PAINT SKYBLUE (-3395 4575);
FORCEPROP 1 LAST VALUE 22
J 2
(-3420 4575);
DISPLAY 0.617021 (-3420 4575);
PAINT SKYBLUE (-3420 4575);
FORCEPROP 2 LAST SEC_TYPE SM
J 0
(-3375 4900);
DISPLAY 1.021277 (-3375 4900);
PAINT ORANGE (-3375 4900);
DISPLAY INVISIBLE (-3375 4900);
FORCEPROP 2 LAST SEC 1
J 0
(-3375 4900);
PAINT MONO (-3375 4900);
DISPLAY INVISIBLE (-3375 4900);
FORCEPROP 2 LAST CDS_LIB mstr_discrete
J 0
(-3300 4675);
PAINT ORANGE (-3300 4675);
DISPLAY INVISIBLE (-3300 4675);
FORCEPROP 1 LAST PATH I82
J 0
(-3395 4840);
DISPLAY 0.872340 (-3395 4840);
PAINT PURPLE (-3395 4840);
DISPLAY INVISIBLE (-3395 4840);
FORCEPROP 2 LAST BOM_COST P5V_STBY_VR
J 0
(-3375 4825);
DISPLAY 1.021277 (-3375 4825);
PAINT ORANGE (-3375 4825);
DISPLAY INVISIBLE (-3375 4825);
FORCEPROP 2 LAST ROOM P5V_STBY_VR
J 0
(-3375 4775);
DISPLAY 1.021277 (-3375 4775);
PAINT ORANGE (-3375 4775);
DISPLAY INVISIBLE (-3375 4775);
FORCEPROP 2 LAST CDS_LOCATION FB7E1
J 0
(-3395 4730);
DISPLAY 0.617021 (-3395 4730);
PAINT AQUA (-3395 4730);
DISPLAY INVISIBLE (-3395 4730);
FORCEADD TPS54821..1
(125 3575);
FORCEPROP 2 LASTPIN (-275 3775) $PN 5
J 2
(-285 3785);
DISPLAY 0.617021 (-285 3785);
PAINT ORANGE (-285 3785);
FORCEPROP 2 LASTPIN (525 3575) $PN 12
J 0
(535 3585);
DISPLAY 0.617021 (535 3585);
PAINT ORANGE (535 3585);
FORCEPROP 2 LASTPIN (525 3675) $PN 13
J 0
(535 3685);
DISPLAY 0.617021 (535 3685);
PAINT ORANGE (535 3685);
FORCEPROP 2 LASTPIN (525 3775) $PN 14
J 0
(535 3785);
DISPLAY 0.617021 (535 3785);
PAINT ORANGE (535 3785);
FORCEPROP 2 LASTPIN (525 3425) $PN 7
J 0
(535 3435);
DISPLAY 0.617021 (535 3435);
PAINT ORANGE (535 3435);
FORCEPROP 2 LASTPIN (525 3525) $PN 11
J 0
(535 3535);
DISPLAY 0.617021 (535 3535);
PAINT ORANGE (535 3535);
FORCEPROP 2 LASTPIN (525 3325) $PN 3
J 0
(535 3335);
DISPLAY 0.617021 (535 3335);
PAINT ORANGE (535 3335);
FORCEPROP 2 LASTPIN (525 3275) $PN 2
J 0
(535 3285);
DISPLAY 0.617021 (535 3285);
PAINT ORANGE (535 3285);
FORCEPROP 2 LASTPIN (525 3225) $PN 15
J 0
(535 3235);
DISPLAY 0.617021 (535 3235);
PAINT ORANGE (535 3235);
FORCEPROP 1 LAST MATERIAL IC
J 0
(-225 3975);
DISPLAY 0.617021 (-225 3975);
PAINT SKYBLUE (-225 3975);
FORCEPROP 1 LAST LOCATION EU7E2
J 0
(-225 4025);
DISPLAY 0.617021 (-225 4025);
PAINT AQUA (-225 4025);
FORCEPROP 2 LASTPIN (-275 3725) $PN 4
J 2
(-285 3735);
DISPLAY 0.617021 (-285 3735);
PAINT ORANGE (-285 3735);
FORCEPROP 2 LASTPIN (-275 3575) $PN 6
J 2
(-285 3585);
DISPLAY 0.617021 (-285 3585);
PAINT ORANGE (-285 3585);
FORCEPROP 2 LASTPIN (-275 3375) $PN 9
J 2
(-285 3385);
DISPLAY 0.617021 (-285 3385);
PAINT ORANGE (-285 3385);
FORCEPROP 2 LASTPIN (-275 3475) $PN 10
J 2
(-285 3485);
DISPLAY 0.617021 (-285 3485);
PAINT ORANGE (-285 3485);
FORCEPROP 2 LASTPIN (-275 3275) $PN 8
J 2
(-285 3285);
DISPLAY 0.617021 (-285 3285);
PAINT ORANGE (-285 3285);
FORCEPROP 1 LAST PART_NUMBER H63269-001
J 0
(-225 3075);
DISPLAY 0.617021 (-225 3075);
PAINT BLUE (-225 3075);
FORCEPROP 2 LASTPIN (-275 3325) $PN 1
J 2
(-285 3335);
DISPLAY 0.617021 (-285 3335);
PAINT ORANGE (-285 3335);
FORCEPROP 2 LAST CDS_LIB mstr_vreg
J 0
(125 3575);
PAINT ORANGE (125 3575);
DISPLAY INVISIBLE (125 3575);
FORCEPROP 1 LAST PATH I83
J 0
(175 3975);
PAINT GREEN (175 3975);
DISPLAY INVISIBLE (175 3975);
FORCEPROP 2 LAST BOM_COST P5V_STBY_VR
J 0
(-225 4125);
DISPLAY 1.021277 (-225 4125);
PAINT ORANGE (-225 4125);
DISPLAY INVISIBLE (-225 4125);
FORCEPROP 1 LAST PACK_TYPE LCC
J 0
(-225 4075);
PAINT SKYBLUE (-225 4075);
DISPLAY INVISIBLE (-225 4075);
FORCEPROP 2 LAST SEC_TYPE LCC
J 0
(-225 4075);
DISPLAY 1.021277 (-225 4075);
PAINT ORANGE (-225 4075);
DISPLAY INVISIBLE (-225 4075);
FORCEPROP 2 LAST SEC 1
J 0
(-225 4075);
DISPLAY 0.680851 (-225 4075);
PAINT MONO (-225 4075);
DISPLAY INVISIBLE (-225 4075);
FORCEPROP 2 LAST ROOM P5V_STBY_VR
J 0
(-225 4075);
DISPLAY 1.021277 (-225 4075);
PAINT ORANGE (-225 4075);
DISPLAY INVISIBLE (-225 4075);
FORCEPROP 2 LAST CDS_LOCATION EU7E2
J 0
(-225 4025);
DISPLAY 0.617021 (-225 4025);
PAINT AQUA (-225 4025);
DISPLAY INVISIBLE (-225 4025);
FORCEADD P5V_STBY..1
(1225 5050);
FORCEPROP 3 LASTPIN (1225 5000) SIG_NAME P5V_STBY\g
J 0
(1235 5010);
DISPLAY 0.659574 (1235 5010);
PAINT MONO (1235 5010);
DISPLAY INVISIBLE (1235 5010);
FORCEPROP 1 LAST VOLTAGE +5.0V
J 0
(1425 5200);
DISPLAY 1.021277 (1425 5200);
PAINT SKYBLUE (1425 5200);
DISPLAY INVISIBLE (1425 5200);
FORCEPROP 2 LAST CDS_LIB mstr_symbols
J 0
(1225 5050);
PAINT ORANGE (1225 5050);
DISPLAY INVISIBLE (1225 5050);
FORCEPROP 1 LAST SIZE 1B
J 0
(1270 5072);
DISPLAY 0.340426 (1270 5072);
PAINT GREEN (1270 5072);
DISPLAY INVISIBLE (1270 5072);
FORCEPROP 1 LAST PATH I85
J 0
(1270 5052);
DISPLAY 0.340426 (1270 5052);
PAINT GREEN (1270 5052);
DISPLAY INVISIBLE (1270 5052);
FORCEPROP 1 LAST BODY_TYPE PLUMBING
J 0
(1180 5007);
DISPLAY 0.340426 (1180 5007);
PAINT GREEN (1180 5007);
DISPLAY INVISIBLE (1180 5007);
FORCEPROP 1 LAST HDL_POWER P5V_STBY
J 0
(925 4925);
DISPLAY 0.872340 (925 4925);
PAINT ORANGE (925 4925);
DISPLAY INVISIBLE (925 4925);
FORCEADD GND..1
(975 2075);
FORCEPROP 3 LASTPIN (975 2125) SIG_NAME AGND_P5V_STBY\g
J 0
(985 2135);
DISPLAY 0.659574 (985 2135);
PAINT MONO (985 2135);
DISPLAY INVISIBLE (985 2135);
FORCEPROP 1 LAST HDL_POWER AGND_P5V_STBY
J 0
(825 2025);
DISPLAY 0.617021 (825 2025);
PAINT GREEN (825 2025);
FORCEPROP 1 LAST PATH I86
J 0
(1050 2075);
DISPLAY 0.872340 (1050 2075);
PAINT AQUA (1050 2075);
DISPLAY INVISIBLE (1050 2075);
FORCEPROP 2 LAST CDS_LIB mstr_symbols
J 0
(975 2075);
PAINT ORANGE (975 2075);
DISPLAY INVISIBLE (975 2075);
FORCEPROP 1 LAST VOLTAGE 0
J 0
(975 2075);
DISPLAY 1.340426 (975 2075);
PAINT SKYBLUE (975 2075);
DISPLAY INVISIBLE (975 2075);
FORCEPROP 1 LAST SIZE 1B
J 0
(1050 2025);
DISPLAY 1.170213 (1050 2025);
PAINT AQUA (1050 2025);
DISPLAY INVISIBLE (1050 2025);
FORCEPROP 1 LAST BODY_TYPE PLUMBING
J 0
(930 2032);
DISPLAY 0.340426 (930 2032);
PAINT GREEN (930 2032);
DISPLAY INVISIBLE (930 2032);
FORCEADD RES..1
(2250 4625);
FORCEPROP 1 LAST MATERIAL CHIP
J 0
(2250 4475);
DISPLAY 0.617021 (2250 4475);
PAINT SKYBLUE (2250 4475);
FORCEPROP 1 LAST TOLERANCE 1.0%
J 0
(2250 4525);
DISPLAY 0.617021 (2250 4525);
PAINT SKYBLUE (2250 4525);
FORCEPROP 1 LAST VALUE 22.1
J 2
(2225 4525);
DISPLAY 0.617021 (2225 4525);
PAINT SKYBLUE (2225 4525);
FORCEPROP 1 LAST PACK_TYPE 0402
J 0
(2500 4475);
DISPLAY 0.617021 (2500 4475);
PAINT SKYBLUE (2500 4475);
FORCEPROP 1 LASTPIN (2350 4625) $PN 2
J 0
(2312 4637);
DISPLAY 0.617021 (2312 4637);
PAINT ORANGE (2312 4637);
FORCEPROP 1 LAST LOCATION R7E15
J 0
(2200 4675);
DISPLAY 0.617021 (2200 4675);
PAINT AQUA (2200 4675);
FORCEPROP 1 LAST PART_NUMBER G21796-250
J 0
(2200 4725);
DISPLAY 0.617021 (2200 4725);
PAINT BLUE (2200 4725);
FORCEPROP 1 LASTPIN (2150 4625) $PN 1
J 0
(2162 4637);
DISPLAY 0.617021 (2162 4637);
PAINT ORANGE (2162 4637);
FORCEPROP 1 LAST WATTAGE 1/16W
J 2
(2225 4475);
DISPLAY 0.617021 (2225 4475);
PAINT SKYBLUE (2225 4475);
FORCEPROP 2 LAST SEC_TYPE 0402
J 0
(2200 4825);
DISPLAY 1.021277 (2200 4825);
PAINT ORANGE (2200 4825);
DISPLAY INVISIBLE (2200 4825);
FORCEPROP 0 LAST ROOM P5V_STBY_VR
J 0
(2200 4825);
DISPLAY 1.021277 (2200 4825);
PAINT ORANGE (2200 4825);
DISPLAY INVISIBLE (2200 4825);
FORCEPROP 1 LAST PATH I89
J 0
(2200 4775);
DISPLAY 0.978723 (2200 4775);
PAINT WHITE (2200 4775);
DISPLAY INVISIBLE (2200 4775);
FORCEPROP 2 LAST CDS_LIB mstr_discrete
J 0
(2250 4625);
PAINT MONO (2250 4625);
DISPLAY INVISIBLE (2250 4625);
FORCEPROP 2 LAST SEC 1
J 0
(2200 4825);
DISPLAY 0.680851 (2200 4825);
PAINT MONO (2200 4825);
DISPLAY INVISIBLE (2200 4825);
FORCEPROP 2 LAST CDS_LOCATION R7E15
J 0
(2200 4675);
DISPLAY 0.617021 (2200 4675);
PAINT AQUA (2200 4675);
DISPLAY INVISIBLE (2200 4675);
FORCEADD RES..2
(2550 3875);
FORCEPROP 1 LAST LOCATION R8E18
J 0
(2595 3950);
DISPLAY 0.617021 (2595 3950);
PAINT AQUA (2595 3950);
FORCEPROP 1 LAST VALUE 1.0K
J 0
(2595 3900);
DISPLAY 0.617021 (2595 3900);
PAINT SKYBLUE (2595 3900);
FORCEPROP 1 LASTPIN (2550 3775) $PN 2
J 0
(2555 3785);
DISPLAY 0.617021 (2555 3785);
PAINT WHITE (2555 3785);
FORCEPROP 1 LASTPIN (2550 3975) $PN 1
J 0
(2555 3937);
DISPLAY 0.617021 (2555 3937);
PAINT WHITE (2555 3937);
FORCEPROP 1 LAST PACK_TYPE 0402
J 0
(2590 3700);
DISPLAY 0.617021 (2590 3700);
PAINT SKYBLUE (2590 3700);
FORCEPROP 1 LAST MATERIAL CHIP
J 0
(2590 3750);
DISPLAY 0.617021 (2590 3750);
PAINT SKYBLUE (2590 3750);
FORCEPROP 1 LAST WATTAGE 1/16W
J 0
(2590 3800);
DISPLAY 0.617021 (2590 3800);
PAINT SKYBLUE (2590 3800);
FORCEPROP 1 LAST TOLERANCE 0.1%
J 0
(2595 3850);
DISPLAY 0.617021 (2595 3850);
PAINT SKYBLUE (2595 3850);
FORCEPROP 1 LAST PART_NUMBER G85996-004
R 1
J 0
(2515 3650);
DISPLAY 0.617021 (2515 3650);
PAINT BLUE (2515 3650);
FORCEPROP 2 LAST SEC_TYPE 0402
J 0
(2600 4100);
DISPLAY 1.361702 (2600 4100);
PAINT ORANGE (2600 4100);
DISPLAY INVISIBLE (2600 4100);
FORCEPROP 2 LAST REUSE_ID 34
J 0
(2600 4100);
DISPLAY 1.361702 (2600 4100);
PAINT ORANGE (2600 4100);
DISPLAY INVISIBLE (2600 4100);
FORCEPROP 2 LAST SEC 1
J 0
(2600 4100);
DISPLAY 0.914894 (2600 4100);
PAINT MONO (2600 4100);
DISPLAY INVISIBLE (2600 4100);
FORCEPROP 2 LAST BOM_COST P5V_STBY_VR
J 0
(2600 4050);
DISPLAY 1.021277 (2600 4050);
PAINT ORANGE (2600 4050);
DISPLAY INVISIBLE (2600 4050);
FORCEPROP 2 LAST CDS_LOCATION R8E18
J 0
(2595 3950);
DISPLAY 0.617021 (2595 3950);
PAINT AQUA (2595 3950);
DISPLAY INVISIBLE (2595 3950);
FORCEPROP 1 LAST PATH I9
J 0
(2600 4050);
DISPLAY 0.978723 (2600 4050);
PAINT WHITE (2600 4050);
DISPLAY INVISIBLE (2600 4050);
FORCEPROP 2 LAST ROOM P5V_STBY_VR
J 0
(2600 4000);
DISPLAY 1.021277 (2600 4000);
PAINT ORANGE (2600 4000);
DISPLAY INVISIBLE (2600 4000);
FORCEPROP 2 LAST CDS_LIB mstr_discrete
J 0
(2550 3875);
DISPLAY 1.340426 (2550 3875);
PAINT ORANGE (2550 3875);
DISPLAY INVISIBLE (2550 3875);
FORCEADD INDUCTOR..1
(2150 4050);
FORCEPROP 1 LAST PART_NUMBER E98761-003
J 0
(2050 4150);
DISPLAY 0.617021 (2050 4150);
PAINT BLUE (2050 4150);
FORCEPROP 1 LAST LOCATION L8E1
J 0
(2050 4100);
DISPLAY 0.617021 (2050 4100);
PAINT AQUA (2050 4100);
FORCEPROP 1 LAST VALUE 2.2UH
J 2
(2145 3965);
DISPLAY 0.617021 (2145 3965);
PAINT SKYBLUE (2145 3965);
FORCEPROP 1 LASTPIN (2250 4050) $PN 2
J 2
(2260 4060);
DISPLAY 0.617021 (2260 4060);
PAINT WHITE (2260 4060);
FORCEPROP 1 LASTPIN (2050 4050) $PN 1
J 0
(2050 4060);
DISPLAY 0.617021 (2050 4060);
PAINT WHITE (2050 4060);
FORCEPROP 1 LAST MATERIAL IND
J 0
(2165 3965);
DISPLAY 0.617021 (2165 3965);
PAINT SKYBLUE (2165 3965);
FORCEPROP 1 LAST PACK_TYPE SM
J 0
(2265 3965);
DISPLAY 0.617021 (2265 3965);
PAINT SKYBLUE (2265 3965);
FORCEPROP 2 LAST $SEC 1
J 0
(2050 4250);
PAINT MONO (2050 4250);
DISPLAY INVISIBLE (2050 4250);
FORCEPROP 2 LAST CDS_SEC 1
J 0
(2050 4250);
PAINT MONO (2050 4250);
DISPLAY INVISIBLE (2050 4250);
FORCEPROP 1 LAST PATH I90
J 0
(2050 4200);
DISPLAY 0.978723 (2050 4200);
PAINT ORANGE (2050 4200);
DISPLAY INVISIBLE (2050 4200);
FORCEPROP 2 LAST CDS_LOCATION L8E1
J 0
(2050 4100);
DISPLAY 0.617021 (2050 4100);
PAINT AQUA (2050 4100);
DISPLAY INVISIBLE (2050 4100);
FORCEPROP 2 LAST CDS_LIB mstr_discrete
J 0
(2150 4050);
PAINT MONO (2150 4050);
DISPLAY INVISIBLE (2150 4050);
FORCEADD RES..1
(-1625 3475);
FORCEPROP 1 LAST LOCATION R8E33
J 0
(-1675 3525);
DISPLAY 0.617021 (-1675 3525);
PAINT AQUA (-1675 3525);
FORCEPROP 1 LASTPIN (-1525 3475) $PN 2
J 0
(-1563 3487);
DISPLAY 0.617021 (-1563 3487);
PAINT ORANGE (-1563 3487);
FORCEPROP 1 LASTPIN (-1725 3475) $PN 1
J 0
(-1713 3487);
DISPLAY 0.617021 (-1713 3487);
PAINT ORANGE (-1713 3487);
FORCEPROP 1 LAST MATERIAL CHIP
J 0
(-1625 3325);
DISPLAY 0.617021 (-1625 3325);
PAINT SKYBLUE (-1625 3325);
FORCEPROP 1 LAST WATTAGE 1/16W
J 2
(-1650 3325);
DISPLAY 0.617021 (-1650 3325);
PAINT SKYBLUE (-1650 3325);
FORCEPROP 1 LAST VALUE 0.0
J 2
(-1725 3375);
DISPLAY 0.617021 (-1725 3375);
PAINT SKYBLUE (-1725 3375);
FORCEPROP 1 LAST PART_NUMBER G21497-005
J 0
(-1775 3425);
DISPLAY 0.617021 (-1775 3425);
PAINT BLUE (-1775 3425);
FORCEPROP 1 LAST TOLERANCE 5%
J 0
(-1675 3375);
DISPLAY 0.617021 (-1675 3375);
PAINT SKYBLUE (-1675 3375);
FORCEPROP 1 LAST PACK_TYPE 0402
J 0
(-1550 3375);
DISPLAY 0.617021 (-1550 3375);
PAINT SKYBLUE (-1550 3375);
FORCEPROP 2 LAST SEC_TYPE 0402
J 0
(-1675 3675);
DISPLAY 1.021277 (-1675 3675);
PAINT ORANGE (-1675 3675);
DISPLAY INVISIBLE (-1675 3675);
FORCEPROP 2 LAST SEC 1
J 0
(-1675 3675);
PAINT MONO (-1675 3675);
DISPLAY INVISIBLE (-1675 3675);
FORCEPROP 1 LAST PATH I91
J 0
(-1675 3625);
DISPLAY 0.978723 (-1675 3625);
PAINT WHITE (-1675 3625);
DISPLAY INVISIBLE (-1675 3625);
FORCEPROP 2 LAST ROOM PVCCIN_CPU0_VR
J 0
(-1675 3575);
DISPLAY 1.361702 (-1675 3575);
PAINT ORANGE (-1675 3575);
DISPLAY INVISIBLE (-1675 3575);
FORCEPROP 2 LAST CDS_LIB mstr_discrete
J 0
(-1625 3475);
PAINT ORANGE (-1625 3475);
DISPLAY INVISIBLE (-1625 3475);
FORCEPROP 2 LAST CDS_LOCATION R8E33
J 0
(-1675 3525);
DISPLAY 0.617021 (-1675 3525);
PAINT AQUA (-1675 3525);
DISPLAY INVISIBLE (-1675 3525);
FORCEADD SC22U16V5MX-4-GP..1
(-2400 4325);
FORCEPROP 2 LAST ATTRIBUTE 22UF
J 0
(-2300 4350);
DISPLAY 0.638298 (-2300 4350);
PAINT GREEN (-2300 4350);
FORCEPROP 2 LAST TOLERANCE 20%
J 0
(-2300 4300);
DISPLAY 0.638298 (-2300 4300);
PAINT GREEN (-2300 4300);
FORCEPROP 1 LAST VALUE SC22U16V5MX-4-GP
R 1
J 0
(-2325 4120);
DISPLAY 0.617021 (-2325 4120);
PAINT GREEN (-2325 4120);
FORCEPROP 2 LAST RATED 16V
J 0
(-2300 4250);
DISPLAY 0.638298 (-2300 4250);
PAINT GREEN (-2300 4250);
FORCEPROP 2 LAST PACK_SIZE 0805
J 0
(-2300 4150);
DISPLAY 0.638298 (-2300 4150);
PAINT GREEN (-2300 4150);
FORCEPROP 2 LAST TYPE X6S
J 0
(-2300 4200);
DISPLAY 0.638298 (-2300 4200);
PAINT GREEN (-2300 4200);
FORCEPROP 1 LAST LOCATION C7E13
J 0
(-2300 4410);
DISPLAY 0.617021 (-2300 4410);
PAINT GREEN (-2300 4410);
FORCEPROP 2 LASTPIN (-2400 4250) $PN 2
R 1
J 2
(-2410 4240);
DISPLAY 0.808511 (-2410 4240);
PAINT ORANGE (-2410 4240);
FORCEPROP 2 LASTPIN (-2400 4400) $PN 1
R 1
J 0
(-2410 4410);
DISPLAY 0.808511 (-2410 4410);
PAINT ORANGE (-2410 4410);
FORCEPROP 1 LAST PATH I92
J 0
(-2400 4325);
DISPLAY 0.617021 (-2400 4325);
PAINT GREEN (-2400 4325);
DISPLAY INVISIBLE (-2400 4325);
FORCEPROP 1 LAST PACK_TYPE SMD-BCG5
J 0
(-2400 4325);
DISPLAY 0.617021 (-2400 4325);
PAINT GREEN (-2400 4325);
DISPLAY INVISIBLE (-2400 4325);
FORCEPROP 2 LAST SEC 1
J 0
(-2375 4400);
DISPLAY 0.680851 (-2375 4400);
PAINT MONO (-2375 4400);
DISPLAY INVISIBLE (-2375 4400);
FORCEPROP 2 LAST SEC_TYPE SMD-BCG5
J 0
(-2375 4400);
DISPLAY 1.021277 (-2375 4400);
PAINT ORANGE (-2375 4400);
DISPLAY INVISIBLE (-2375 4400);
FORCEPROP 1 LAST PART_NUMBER 078.22611.0811
J 0
(-2400 4325);
DISPLAY 0.617021 (-2400 4325);
PAINT GREEN (-2400 4325);
DISPLAY INVISIBLE (-2400 4325);
FORCEPROP 2 LAST CDS_LIB w_hdl
J 0
(-2400 4325);
PAINT MONO (-2400 4325);
DISPLAY INVISIBLE (-2400 4325);
FORCEPROP 1 LAST CDS_LMAN_SYM_OUTLINE -50,25,50,-25
J 0
(-2400 4325);
DISPLAY 0.468085 (-2400 4325);
PAINT GREEN (-2400 4325);
DISPLAY INVISIBLE (-2400 4325);
FORCEADD GND..1
(-2100 4075);
FORCEPROP 3 LASTPIN (-2100 4125) SIG_NAME GND\g
J 0
(-2090 4135);
DISPLAY 0.659574 (-2090 4135);
PAINT MONO (-2090 4135);
DISPLAY INVISIBLE (-2090 4135);
FORCEPROP 1 LAST PATH I93
J 0
(-2025 4075);
DISPLAY 0.872340 (-2025 4075);
PAINT AQUA (-2025 4075);
DISPLAY INVISIBLE (-2025 4075);
FORCEPROP 2 LAST CDS_LIB mstr_symbols
J 0
(-2100 4075);
PAINT MONO (-2100 4075);
DISPLAY INVISIBLE (-2100 4075);
FORCEPROP 2 LAST BOM_COST PVPP_KLM_VR
J 0
(-2950 4150);
DISPLAY 1.042553 (-2950 4150);
PAINT WHITE (-2950 4150);
DISPLAY INVISIBLE (-2950 4150);
FORCEPROP 2 LAST ROOM PVPP_KLM_VR
J 0
(-2675 4150);
DISPLAY 1.042553 (-2675 4150);
PAINT GREEN (-2675 4150);
DISPLAY INVISIBLE (-2675 4150);
FORCEPROP 1 LAST VOLTAGE 0
J 0
(-2100 4075);
PAINT SKYBLUE (-2100 4075);
DISPLAY INVISIBLE (-2100 4075);
FORCEPROP 1 LAST SIZE 1B
J 0
(-2025 4025);
DISPLAY 0.872340 (-2025 4025);
PAINT GREEN (-2025 4025);
DISPLAY INVISIBLE (-2025 4025);
FORCEPROP 1 LAST BODY_TYPE PLUMBING
J 0
(-2145 4032);
DISPLAY 0.340426 (-2145 4032);
PAINT GREEN (-2145 4032);
DISPLAY INVISIBLE (-2145 4032);
FORCEPROP 1 LAST HDL_POWER GND
J 0
(-2100 4225);
DISPLAY 0.872340 (-2100 4225);
PAINT GREEN (-2100 4225);
DISPLAY INVISIBLE (-2100 4225);
FORCEADD GND..1
(-2400 4075);
FORCEPROP 3 LASTPIN (-2400 4125) SIG_NAME GND\g
J 0
(-2390 4135);
DISPLAY 0.659574 (-2390 4135);
PAINT MONO (-2390 4135);
DISPLAY INVISIBLE (-2390 4135);
FORCEPROP 1 LAST PATH I94
J 0
(-2325 4075);
DISPLAY 0.872340 (-2325 4075);
PAINT AQUA (-2325 4075);
DISPLAY INVISIBLE (-2325 4075);
FORCEPROP 2 LAST CDS_LIB mstr_symbols
J 0
(-2400 4075);
PAINT MONO (-2400 4075);
DISPLAY INVISIBLE (-2400 4075);
FORCEPROP 2 LAST BOM_COST PVPP_KLM_VR
J 0
(-3250 4150);
DISPLAY 1.042553 (-3250 4150);
PAINT WHITE (-3250 4150);
DISPLAY INVISIBLE (-3250 4150);
FORCEPROP 2 LAST ROOM PVPP_KLM_VR
J 0
(-2975 4150);
DISPLAY 1.042553 (-2975 4150);
PAINT GREEN (-2975 4150);
DISPLAY INVISIBLE (-2975 4150);
FORCEPROP 1 LAST VOLTAGE 0
J 0
(-2400 4075);
PAINT SKYBLUE (-2400 4075);
DISPLAY INVISIBLE (-2400 4075);
FORCEPROP 1 LAST SIZE 1B
J 0
(-2325 4025);
DISPLAY 0.872340 (-2325 4025);
PAINT GREEN (-2325 4025);
DISPLAY INVISIBLE (-2325 4025);
FORCEPROP 1 LAST BODY_TYPE PLUMBING
J 0
(-2445 4032);
DISPLAY 0.340426 (-2445 4032);
PAINT GREEN (-2445 4032);
DISPLAY INVISIBLE (-2445 4032);
FORCEPROP 1 LAST HDL_POWER GND
J 0
(-2400 4225);
DISPLAY 0.872340 (-2400 4225);
PAINT GREEN (-2400 4225);
DISPLAY INVISIBLE (-2400 4225);
FORCEADD SC22U16V5MX-4-GP..1
(-2100 4325);
FORCEPROP 1 LAST LOCATION C22W9
J 0
(-2000 4410);
DISPLAY 0.617021 (-2000 4410);
PAINT GREEN (-2000 4410);
FORCEPROP 2 LAST ATTRIBUTE 22UF
J 0
(-2000 4350);
DISPLAY 0.638298 (-2000 4350);
PAINT GREEN (-2000 4350);
FORCEPROP 1 LAST VALUE SC22U16V5MX-4-GP
R 1
J 0
(-2025 4120);
DISPLAY 0.617021 (-2025 4120);
PAINT GREEN (-2025 4120);
FORCEPROP 2 LAST TOLERANCE 20%
J 0
(-2000 4300);
DISPLAY 0.638298 (-2000 4300);
PAINT GREEN (-2000 4300);
FORCEPROP 2 LASTPIN (-2100 4250) $PN 2
R 1
J 2
(-2110 4240);
DISPLAY 0.808511 (-2110 4240);
PAINT ORANGE (-2110 4240);
FORCEPROP 2 LAST PACK_SIZE 0805
J 0
(-2000 4150);
DISPLAY 0.638298 (-2000 4150);
PAINT GREEN (-2000 4150);
FORCEPROP 2 LAST TYPE X6S
J 0
(-2000 4200);
DISPLAY 0.638298 (-2000 4200);
PAINT GREEN (-2000 4200);
FORCEPROP 2 LASTPIN (-2100 4400) $PN 1
R 1
J 0
(-2110 4410);
DISPLAY 0.808511 (-2110 4410);
PAINT ORANGE (-2110 4410);
FORCEPROP 2 LAST RATED 16V
J 0
(-2000 4250);
DISPLAY 0.638298 (-2000 4250);
PAINT GREEN (-2000 4250);
FORCEPROP 1 LAST PATH I95
J 0
(-2100 4325);
DISPLAY 0.617021 (-2100 4325);
PAINT GREEN (-2100 4325);
DISPLAY INVISIBLE (-2100 4325);
FORCEPROP 1 LAST CDS_LMAN_SYM_OUTLINE -50,25,50,-25
J 0
(-2100 4325);
DISPLAY 0.468085 (-2100 4325);
PAINT GREEN (-2100 4325);
DISPLAY INVISIBLE (-2100 4325);
FORCEPROP 2 LAST CDS_LIB w_hdl
J 0
(-2100 4325);
PAINT MONO (-2100 4325);
DISPLAY INVISIBLE (-2100 4325);
FORCEPROP 1 LAST PART_NUMBER 078.22611.0811
J 0
(-2100 4325);
DISPLAY 0.617021 (-2100 4325);
PAINT GREEN (-2100 4325);
DISPLAY INVISIBLE (-2100 4325);
FORCEPROP 2 LAST SEC_TYPE SMD-BCG5
J 0
(-2075 4400);
DISPLAY 1.021277 (-2075 4400);
PAINT ORANGE (-2075 4400);
DISPLAY INVISIBLE (-2075 4400);
FORCEPROP 2 LAST SEC 1
J 0
(-2075 4400);
DISPLAY 0.680851 (-2075 4400);
PAINT MONO (-2075 4400);
DISPLAY INVISIBLE (-2075 4400);
FORCEPROP 1 LAST PACK_TYPE SMD-BCG5
J 0
(-2100 4325);
DISPLAY 0.617021 (-2100 4325);
PAINT GREEN (-2100 4325);
DISPLAY INVISIBLE (-2100 4325);
FORCEADD SC22U16V5MX-4-GP..1
(-2750 4325);
FORCEPROP 2 LAST RATED 16V
J 0
(-2650 4250);
DISPLAY 0.638298 (-2650 4250);
PAINT GREEN (-2650 4250);
FORCEPROP 1 LAST VALUE SC22U16V5MX-4-GP
R 1
J 0
(-2675 4120);
DISPLAY 0.617021 (-2675 4120);
PAINT GREEN (-2675 4120);
FORCEPROP 2 LASTPIN (-2750 4250) $PN 2
R 1
J 2
(-2760 4240);
DISPLAY 0.808511 (-2760 4240);
PAINT ORANGE (-2760 4240);
FORCEPROP 1 LAST LOCATION C22W8
J 0
(-2650 4410);
DISPLAY 0.617021 (-2650 4410);
PAINT GREEN (-2650 4410);
FORCEPROP 2 LAST ATTRIBUTE 22UF
J 0
(-2650 4350);
DISPLAY 0.638298 (-2650 4350);
PAINT GREEN (-2650 4350);
FORCEPROP 2 LAST TYPE X6S
J 0
(-2650 4200);
DISPLAY 0.638298 (-2650 4200);
PAINT GREEN (-2650 4200);
FORCEPROP 2 LAST PACK_SIZE 0805
J 0
(-2650 4150);
DISPLAY 0.638298 (-2650 4150);
PAINT GREEN (-2650 4150);
FORCEPROP 2 LAST TOLERANCE 20%
J 0
(-2650 4300);
DISPLAY 0.638298 (-2650 4300);
PAINT GREEN (-2650 4300);
FORCEPROP 2 LASTPIN (-2750 4400) $PN 1
R 1
J 0
(-2760 4410);
DISPLAY 0.808511 (-2760 4410);
PAINT ORANGE (-2760 4410);
FORCEPROP 1 LAST PATH I96
J 0
(-2750 4325);
DISPLAY 0.617021 (-2750 4325);
PAINT GREEN (-2750 4325);
DISPLAY INVISIBLE (-2750 4325);
FORCEPROP 1 LAST PACK_TYPE SMD-BCG5
J 0
(-2750 4325);
DISPLAY 0.617021 (-2750 4325);
PAINT GREEN (-2750 4325);
DISPLAY INVISIBLE (-2750 4325);
FORCEPROP 2 LAST SEC 1
J 0
(-2725 4400);
DISPLAY 0.680851 (-2725 4400);
PAINT MONO (-2725 4400);
DISPLAY INVISIBLE (-2725 4400);
FORCEPROP 2 LAST SEC_TYPE SMD-BCG5
J 0
(-2725 4400);
DISPLAY 1.021277 (-2725 4400);
PAINT ORANGE (-2725 4400);
DISPLAY INVISIBLE (-2725 4400);
FORCEPROP 1 LAST PART_NUMBER 078.22611.0811
J 0
(-2750 4325);
DISPLAY 0.617021 (-2750 4325);
PAINT GREEN (-2750 4325);
DISPLAY INVISIBLE (-2750 4325);
FORCEPROP 2 LAST CDS_LIB w_hdl
J 0
(-2750 4325);
PAINT MONO (-2750 4325);
DISPLAY INVISIBLE (-2750 4325);
FORCEPROP 1 LAST CDS_LMAN_SYM_OUTLINE -50,25,50,-25
J 0
(-2750 4325);
DISPLAY 0.468085 (-2750 4325);
PAINT GREEN (-2750 4325);
DISPLAY INVISIBLE (-2750 4325);
FORCEADD GND..1
(-2750 4075);
FORCEPROP 3 LASTPIN (-2750 4125) SIG_NAME GND\g
J 0
(-2740 4135);
DISPLAY 0.659574 (-2740 4135);
PAINT MONO (-2740 4135);
DISPLAY INVISIBLE (-2740 4135);
FORCEPROP 1 LAST PATH I97
J 0
(-2675 4075);
DISPLAY 0.872340 (-2675 4075);
PAINT AQUA (-2675 4075);
DISPLAY INVISIBLE (-2675 4075);
FORCEPROP 1 LAST SIZE 1B
J 0
(-2675 4025);
DISPLAY 0.872340 (-2675 4025);
PAINT GREEN (-2675 4025);
DISPLAY INVISIBLE (-2675 4025);
FORCEPROP 1 LAST VOLTAGE 0
J 0
(-2750 4075);
PAINT SKYBLUE (-2750 4075);
DISPLAY INVISIBLE (-2750 4075);
FORCEPROP 2 LAST ROOM PVPP_KLM_VR
J 0
(-3325 4150);
DISPLAY 1.042553 (-3325 4150);
PAINT GREEN (-3325 4150);
DISPLAY INVISIBLE (-3325 4150);
FORCEPROP 2 LAST BOM_COST PVPP_KLM_VR
J 0
(-3600 4150);
DISPLAY 1.042553 (-3600 4150);
PAINT WHITE (-3600 4150);
DISPLAY INVISIBLE (-3600 4150);
FORCEPROP 2 LAST CDS_LIB mstr_symbols
J 0
(-2750 4075);
PAINT MONO (-2750 4075);
DISPLAY INVISIBLE (-2750 4075);
FORCEPROP 1 LAST BODY_TYPE PLUMBING
J 0
(-2795 4032);
DISPLAY 0.340426 (-2795 4032);
PAINT GREEN (-2795 4032);
DISPLAY INVISIBLE (-2795 4032);
FORCEPROP 1 LAST HDL_POWER GND
J 0
(-2750 4225);
DISPLAY 0.872340 (-2750 4225);
PAINT GREEN (-2750 4225);
DISPLAY INVISIBLE (-2750 4225);
FORCEADD SC22U16V5MX-4-GP..1
(-3050 4325);
FORCEPROP 2 LAST PACK_SIZE 0805
J 0
(-2950 4150);
DISPLAY 0.638298 (-2950 4150);
PAINT GREEN (-2950 4150);
FORCEPROP 2 LAST TYPE X6S
J 0
(-2950 4200);
DISPLAY 0.638298 (-2950 4200);
PAINT GREEN (-2950 4200);
FORCEPROP 2 LAST RATED 16V
J 0
(-2950 4250);
DISPLAY 0.638298 (-2950 4250);
PAINT GREEN (-2950 4250);
FORCEPROP 2 LAST TOLERANCE 20%
J 0
(-2950 4300);
DISPLAY 0.638298 (-2950 4300);
PAINT GREEN (-2950 4300);
FORCEPROP 2 LAST ATTRIBUTE 22UF
J 0
(-2950 4350);
DISPLAY 0.638298 (-2950 4350);
PAINT GREEN (-2950 4350);
FORCEPROP 1 LAST LOCATION C7E12
J 0
(-2950 4410);
DISPLAY 0.617021 (-2950 4410);
PAINT GREEN (-2950 4410);
FORCEPROP 2 LASTPIN (-3050 4400) $PN 1
R 1
J 0
(-3060 4410);
DISPLAY 0.808511 (-3060 4410);
PAINT ORANGE (-3060 4410);
FORCEPROP 2 LASTPIN (-3050 4250) $PN 2
R 1
J 2
(-3060 4240);
DISPLAY 0.808511 (-3060 4240);
PAINT ORANGE (-3060 4240);
FORCEPROP 1 LAST VALUE SC22U16V5MX-4-GP
R 1
J 0
(-2975 4120);
DISPLAY 0.617021 (-2975 4120);
PAINT GREEN (-2975 4120);
FORCEPROP 1 LAST PATH I98
J 0
(-3050 4325);
DISPLAY 0.617021 (-3050 4325);
PAINT GREEN (-3050 4325);
DISPLAY INVISIBLE (-3050 4325);
FORCEPROP 1 LAST CDS_LMAN_SYM_OUTLINE -50,25,50,-25
J 0
(-3050 4325);
DISPLAY 0.468085 (-3050 4325);
PAINT GREEN (-3050 4325);
DISPLAY INVISIBLE (-3050 4325);
FORCEPROP 2 LAST CDS_LIB w_hdl
J 0
(-3050 4325);
PAINT MONO (-3050 4325);
DISPLAY INVISIBLE (-3050 4325);
FORCEPROP 1 LAST PART_NUMBER 078.22611.0811
J 0
(-3050 4325);
DISPLAY 0.617021 (-3050 4325);
PAINT GREEN (-3050 4325);
DISPLAY INVISIBLE (-3050 4325);
FORCEPROP 2 LAST SEC_TYPE SMD-BCG5
J 0
(-3025 4400);
DISPLAY 1.021277 (-3025 4400);
PAINT ORANGE (-3025 4400);
DISPLAY INVISIBLE (-3025 4400);
FORCEPROP 2 LAST SEC 1
J 0
(-3025 4400);
DISPLAY 0.680851 (-3025 4400);
PAINT MONO (-3025 4400);
DISPLAY INVISIBLE (-3025 4400);
FORCEPROP 1 LAST PACK_TYPE SMD-BCG5
J 0
(-3050 4325);
DISPLAY 0.617021 (-3050 4325);
PAINT GREEN (-3050 4325);
DISPLAY INVISIBLE (-3050 4325);
FORCEADD GND..1
(-3050 4075);
FORCEPROP 3 LASTPIN (-3050 4125) SIG_NAME GND\g
J 0
(-3040 4135);
DISPLAY 0.659574 (-3040 4135);
PAINT MONO (-3040 4135);
DISPLAY INVISIBLE (-3040 4135);
FORCEPROP 1 LAST PATH I99
J 0
(-2975 4075);
DISPLAY 0.872340 (-2975 4075);
PAINT AQUA (-2975 4075);
DISPLAY INVISIBLE (-2975 4075);
FORCEPROP 1 LAST SIZE 1B
J 0
(-2975 4025);
DISPLAY 0.872340 (-2975 4025);
PAINT GREEN (-2975 4025);
DISPLAY INVISIBLE (-2975 4025);
FORCEPROP 1 LAST VOLTAGE 0
J 0
(-3050 4075);
PAINT SKYBLUE (-3050 4075);
DISPLAY INVISIBLE (-3050 4075);
FORCEPROP 2 LAST ROOM PVPP_KLM_VR
J 0
(-3625 4150);
DISPLAY 1.042553 (-3625 4150);
PAINT GREEN (-3625 4150);
DISPLAY INVISIBLE (-3625 4150);
FORCEPROP 2 LAST BOM_COST PVPP_KLM_VR
J 0
(-3900 4150);
DISPLAY 1.042553 (-3900 4150);
PAINT WHITE (-3900 4150);
DISPLAY INVISIBLE (-3900 4150);
FORCEPROP 2 LAST CDS_LIB mstr_symbols
J 0
(-3050 4075);
PAINT MONO (-3050 4075);
DISPLAY INVISIBLE (-3050 4075);
FORCEPROP 1 LAST BODY_TYPE PLUMBING
J 0
(-3095 4032);
DISPLAY 0.340426 (-3095 4032);
PAINT GREEN (-3095 4032);
DISPLAY INVISIBLE (-3095 4032);
FORCEPROP 1 LAST HDL_POWER GND
J 0
(-3050 4225);
DISPLAY 0.872340 (-3050 4225);
PAINT GREEN (-3050 4225);
DISPLAY INVISIBLE (-3050 4225);
FORCEADD CAD_NOTE..1
(-750 4500);
FORCEPROP 0 LAST LINE2 AND CLOSE TO IC PINS
J 0
(-900 4300);
PAINT WHITE (-900 4300);
FORCEPROP 0 LAST LINE PLACE DECOUPLING SAME SIDE
J 0
(-900 4375);
PAINT WHITE (-900 4375);
FORCEPROP 2 LAST CDS_LIB mstr_symbols
J 0
(-750 4500);
DISPLAY 1.340426 (-750 4500);
PAINT MONO (-750 4500);
DISPLAY INVISIBLE (-750 4500);
FORCEPROP 1 LAST COMMENT_BODY TRUE
J 0
(-725 4600);
DISPLAY 1.340426 (-725 4600);
PAINT GREEN (-725 4600);
DISPLAY INVISIBLE (-725 4600);
FORCEADD DNS..2
(-1995 3070);
PAINT RED (-1995 3070);
FORCEPROP 2 LAST CDS_LIB mstr_misc
J 0
(-1995 3070);
PAINT ORANGE (-1995 3070);
DISPLAY INVISIBLE (-1995 3070);
FORCEPROP 1 LAST COMMENT_BODY TRUE
R 1
J 0
(-1920 2845);
DISPLAY 0.872340 (-1920 2845);
PAINT GREEN (-1920 2845);
DISPLAY INVISIBLE (-1920 2845);
FORCEADD DESIGN_NOTE..1
(2775 2875);
FORCEPROP 0 LAST L8 
J 0
(2625 2050);
PAINT WHITE (2625 2050);
FORCEPROP 0 LAST L10 
J 0
(2625 2350);
PAINT WHITE (2625 2350);
FORCEPROP 0 LAST L2 VOUT = 5.0 V
J 0
(2625 2650);
PAINT WHITE (2625 2650);
FORCEPROP 0 LAST L9 VIN=FSW=650KHZ
J 0
(2625 2200);
PAINT WHITE (2625 2200);
FORCEPROP 0 LAST L5 STEP RATE= TBDA/US
J 0
(2625 2275);
PAINT WHITE (2625 2275);
FORCEPROP 0 LAST L6 AC TOLERANCE = +- 2.5 %
J 0
(2625 2350);
PAINT WHITE (2625 2350);
FORCEPROP 0 LAST L7 DC TOLERANCE = +- 2 %
J 0
(2625 2425);
PAINT WHITE (2625 2425);
FORCEPROP 0 LAST L1 P5V_STBY VR SPECIFICATION
J 0
(2575 2750);
PAINT WHITE (2575 2750);
FORCEPROP 0 LAST L3 TDC = 4.33 A
J 0
(2625 2575);
PAINT WHITE (2625 2575);
FORCEPROP 0 LAST L4 IMAX = 7.05A
J 0
(2625 2500);
PAINT WHITE (2625 2500);
FORCEPROP 2 LAST CDS_LIB mstr_symbols
J 0
(2775 2875);
DISPLAY 1.340426 (2775 2875);
PAINT MONO (2775 2875);
DISPLAY INVISIBLE (2775 2875);
FORCEPROP 1 LAST COMMENT_BODY TRUE
J 0
(2800 2975);
DISPLAY 1.319149 (2800 2975);
PAINT ORANGE (2800 2975);
DISPLAY INVISIBLE (2800 2975);
FORCEADD INTEL_CORP_BPAGE..1
(4250 200);
FORCEPROP 1 LAST CDS_CON_LAST_MODIFIED Fri Jun 16 17:49:27 2017
J 0
(2825 525);
PAINT ORANGE (2825 525);
DISPLAY INVISIBLE (2825 525);
FORCEPROP 1 LAST CUSTOM_TXT_CDS <CURRENT_DESIGN_SHEET> OF <TOTAL_DESIGN_SHEETS>
J 0
(3750 225);
PAINT ORANGE (3750 225);
FORCEPROP 1 LAST CUSTOM_TXT_CDS <CON_LAST_MODIFIED>
J 0
(250 300);
PAINT ORANGE (250 300);
FORCEPROP 2 LAST CUSTOM_TXT_CDS <XR_PAGE_TITLE>
J 0
(-3640 5450);
DISPLAY 0.638298 (-3640 5450);
PAINT PINK (-3640 5450);
DISPLAY INVISIBLE (-3640 5450);
FORCEPROP 1 LAST SCH_TITLE P5V STBY VR
J 0
(-3700 250);
DISPLAY 1.212766 (-3700 250);
PAINT ORANGE (-3700 250);
FORCEPROP 2 LAST CDS_LIB mstr_symbols
J 0
(4250 200);
PAINT MONO (4250 200);
DISPLAY INVISIBLE (4250 200);
FORCEPROP 2 LAST PAGE_BORDER TRUE
J 0
(-3640 5450);
DISPLAY 0.638298 (-3640 5450);
PAINT PINK (-3640 5450);
DISPLAY INVISIBLE (-3640 5450);
FORCEPROP 1 LAST COMMENT_BODY TRUE
J 0
(4262 212);
DISPLAY 0.468085 (4262 212);
PAINT GREEN (4262 212);
DISPLAY INVISIBLE (4262 212);
FORCEPROP 2 LAST CDS_XR_PAGE_TITLE CR-241 : @BASEBOARD_FAB2_LIB.BASEBOARD_FAB2(SCH_1):PAGE241
J 0
(-3640 5450);
DISPLAY 0.638298 (-3640 5450);
PAINT PINK (-3640 5450);
DISPLAY INVISIBLE (-3640 5450);
WIRE 16 -1 (1500 4200)(1500 4300);
WIRE 16 -1 (675 3175)(675 3225);
WIRE 16 -1 (675 3275)(675 3225);
WIRE 16 -1 (525 3225)(675 3225);
WIRE 16 -1 (675 3275)(675 3325);
WIRE 16 -1 (675 3275)(525 3275);
WIRE 16 -1 (675 3325)(525 3325);
WIRE 16 -1 (-1400 3750)(-1400 3600);
WIRE 16 -1 (-2000 2750)(-2000 2975);
WIRE 16 -1 (3800 3550)(3800 3500);
WIRE 16 -1 (3400 3550)(3800 3550);
WIRE 16 -1 (3800 3750)(3800 3550);
WIRE 16 -1 (2850 3550)(3400 3550);
WIRE 16 -1 (3400 3750)(3400 3550);
WIRE 16 -1 (2550 3550)(2850 3550);
WIRE 16 -1 (2850 3750)(2850 3550);
WIRE 16 -1 (2550 3775)(2550 3550);
WIRE 16 -1 (-1750 4100)(-1750 4175);
WIRE 16 -1 (1750 2800)(1750 2675);
WIRE 16 -1 (1925 1550)(1925 1375);
WIRE 16 -1 (1925 1550)(1675 1550);
WIRE 16 -1 (1350 1375)(1350 1550);
WIRE 16 -1 (1475 1550)(1350 1550);
WIRE 16 -1 (-925 2250)(-925 2350);
WIRE 16 -1 (-825 2350)(-925 2350);
WIRE 16 -1 (-925 2350)(-1025 2350);
WIRE 16 -1 (-1025 2900)(-1025 2350);
WIRE 16 -1 (-825 2500)(-825 2350);
WIRE 16 -1 (3800 4200)(3800 4050);
WIRE 16 -1 (3800 4050)(3400 4050);
WIRE 16 -1 (3800 3900)(3800 4050);
WIRE 16 -1 (2850 4050)(3400 4050);
WIRE 16 -1 (3400 3900)(3400 4050);
WIRE 16 -1 (2550 4050)(2850 4050);
WIRE 16 -1 (2850 4050)(2850 3900);
WIRE 16 -1 (2375 4050)(2550 4050);
WIRE 16 -1 (2550 3975)(2550 4050);
WIRE 16 -1 (2375 3650)(2375 4050);
WIRE 16 -1 (2250 4050)(2375 4050);
WIRE 16 -1 (2175 3650)(2375 3650);
WIRE 16 -1 (-3525 4825)(-3525 4675);
WIRE 16 -1 (-3525 4675)(-3400 4675);
WIRE 16 -1 (1225 4950)(1225 5000);
WIRE 16 -1 (975 2125)(975 2200);
WIRE 16 -1 (975 2575)(975 2200);
WIRE 16 -1 (675 2200)(975 2200);
WIRE 16 -1 (300 2575)(975 2575);
WIRE 16 -1 (-2100 4250)(-2100 4125);
WIRE 16 -1 (-2400 4250)(-2400 4125);
WIRE 16 -1 (-2750 4250)(-2750 4125);
WIRE 16 -1 (-3050 4250)(-3050 4125);
WIRE 16 -1 (-3200 4675)(-3100 4675);
WIRE 16 -1 (-3100 4675)(-3100 4525);
WIRE 16 -1 (-3050 4525)(-3100 4525);
WIRE 16 -1 (-3050 4400)(-3050 4525);
WIRE 16 -1 (-3050 4525)(-2750 4525);
WIRE 16 -1 (-2750 4525)(-2750 4400);
WIRE 16 -1 (-2750 4525)(-2400 4525);
WIRE 16 -1 (-2400 4400)(-2400 4525);
WIRE 16 -1 (-2400 4525)(-2100 4525);
WIRE 16 -1 (-2100 4525)(-2100 4400);
WIRE 16 -1 (-2100 4525)(-1750 4525);
WIRE 16 -1 (-1750 4375)(-1750 4525);
WIRE 16 -1 (-275 3725)(-400 3725);
WIRE 16 -1 (-400 3725)(-400 3775);
WIRE 16 -1 (-400 3775)(-275 3775);
WIRE 16 -1 (-1750 4525)(-1400 4525);
WIRE 16 -1 (-1400 4300)(-1400 4525);
WIRE 16 -1 (-1050 4525)(-1400 4525);
WIRE 16 -1 (-450 3775)(-400 3775);
WIRE 16 -1 (-450 4125)(-450 3775);
WIRE 16 -1 (-1050 4125)(-1050 4525);
WIRE 16 -1 (-1050 4125)(-450 4125);
FORCEPROP 0 LAST SIG_NAME VR_FET_SW_P5V_STBY_PVIN
J 0
(-1010 4160);
DISPLAY 0.617021 (-1010 4160);
PAINT ORANGE (-1010 4160);
FORCEPROP 2 LASTPROP $XRERR UNIQUE?
J 0
(-1250 4160);
DISPLAY 0.638298 (-1250 4160);
PAINT MONO (-1250 4160);
DISPLAY INVISIBLE (-1250 4160);
WIRE 16 -1 (1400 3425)(525 3425);
FORCEPROP 2 LAST SIG_NAME VR_P5V_STBY_VSENSE
J 0
(665 3435);
DISPLAY 0.617021 (665 3435);
PAINT ORANGE (665 3435);
FORCEPROP 2 LASTPROP $XRERR UNIQUE?
J 0
(425 3435);
DISPLAY 0.638298 (425 3435);
PAINT MONO (425 3435);
DISPLAY INVISIBLE (425 3435);
WIRE 16 -1 (1400 3150)(1400 3425);
WIRE 16 -1 (1750 3150)(1750 3000);
WIRE 16 -1 (1750 3150)(1400 3150);
WIRE 16 -1 (1750 3325)(1750 3150);
WIRE 16 2175 (3950 2000)(3950 2825);
WIRE 16 2175 (2375 2825)(3950 2825);
WIRE 16 2175 (3950 2000)(2375 2000);
WIRE 16 2175 (2375 2000)(2375 2825);
WIRE 16 2175 (1550 3900)(2325 3900);
WIRE 16 2175 (2325 3900)(2325 2975);
WIRE 16 2175 (1550 2400)(1550 3900);
WIRE 16 2175 (2075 2400)(1550 2400);
WIRE 16 2175 (2325 2975)(2075 2975);
WIRE 16 2175 (2075 2975)(2075 2400);
WIRE 16 2175 (-1500 4000)(-3350 4000);
WIRE 16 2175 (-1500 4000)(-1500 4475);
WIRE 16 2175 (-3350 4000)(-3350 4475);
WIRE 16 2175 (-3350 4475)(-1500 4475);
WIRE 16 -1 (-1525 3475)(-275 3475);
FORCEPROP 2 LAST SIG_NAME VR_P5V_STBY_EN
J 0
(-1055 3485);
DISPLAY 0.617021 (-1055 3485);
PAINT ORANGE (-1055 3485);
FORCEPROP 2 LASTPROP $XRERR UNIQUE?
J 0
(-1295 3485);
DISPLAY 0.638298 (-1295 3485);
PAINT MONO (-1295 3485);
DISPLAY INVISIBLE (-1295 3485);
WIRE 16 -1 (-1400 4025)(-1400 3950);
WIRE 16 -1 (-1400 4100)(-1400 4025);
WIRE 16 -1 (-550 3575)(-275 3575);
WIRE 16 -1 (-550 4025)(-1400 4025);
FORCEPROP 2 LAST SIG_NAME VR_P5V_STBY_VIN
J 0
(-1310 4035);
DISPLAY 0.617021 (-1310 4035);
PAINT ORANGE (-1310 4035);
FORCEPROP 2 LASTPROP $XRERR UNIQUE?
J 0
(-1550 4035);
DISPLAY 0.638298 (-1550 4035);
PAINT MONO (-1550 4035);
DISPLAY INVISIBLE (-1550 4035);
WIRE 16 -1 (-550 4025)(-550 3575);
WIRE 3 682 (2750 4150)(2750 3350);
WIRE 3 682 (4200 4150)(2750 4150);
WIRE 3 682 (2750 3350)(4200 3350);
WIRE 3 682 (4200 3350)(4200 4150);
WIRE 3 682 (3300 4100)(3300 3400);
WIRE 3 682 (4150 4100)(3300 4100);
WIRE 3 682 (3300 3400)(4150 3400);
WIRE 3 682 (4150 3400)(4150 4100);
WIRE 16 -1 (2050 4050)(1400 4050);
FORCEPROP 2 LAST SIG_NAME VR_P5V_STBY_PHASE
J 0
(1465 4060);
DISPLAY 0.617021 (1465 4060);
PAINT ORANGE (1465 4060);
FORCEPROP 2 LASTPROP $XRERR UNIQUE?
J 0
(1225 4060);
DISPLAY 0.638298 (1225 4060);
PAINT MONO (1225 4060);
DISPLAY INVISIBLE (1225 4060);
WIRE 16 -1 (1400 3675)(1300 3675);
WIRE 16 -1 (1400 4050)(1400 3675);
WIRE 16 -1 (1400 3575)(525 3575);
WIRE 16 -1 (1400 3575)(1400 3675);
WIRE 16 -1 (1400 3525)(1400 3575);
WIRE 16 -1 (525 3525)(1400 3525);
WIRE 16 2175 (900 3600)(900 4000);
WIRE 16 2175 (1500 3600)(900 3600);
WIRE 16 2175 (900 4000)(1500 4000);
WIRE 16 2175 (1500 4000)(1500 3600);
WIRE 16 -1 (-1025 3375)(-275 3375);
FORCEPROP 2 LAST SIG_NAME VR_P5V_STBY_SS
J 0
(-930 3385);
DISPLAY 0.617021 (-930 3385);
PAINT ORANGE (-930 3385);
FORCEPROP 2 LASTPROP $XRERR UNIQUE?
J 0
(-1170 3385);
DISPLAY 0.638298 (-1170 3385);
PAINT MONO (-1170 3385);
DISPLAY INVISIBLE (-1170 3385);
WIRE 16 -1 (-1025 3100)(-1025 3375);
WIRE 16 -1 (-100 2200)(475 2200);
FORCEPROP 0 LAST SIG_NAME VR_P5V_STBY_RC_COMP
J 0
(-10 2210);
DISPLAY 0.617021 (-10 2210);
PAINT ORANGE (-10 2210);
FORCEPROP 2 LASTPROP $XRERR UNIQUE?
J 0
(-250 2210);
DISPLAY 0.638298 (-250 2210);
PAINT MONO (-250 2210);
DISPLAY INVISIBLE (-250 2210);
WIRE 16 -1 (2350 4625)(2975 4625);
FORCEPROP 2 LAST SIG_NAME PWRGD_P5V_STBY
J 0
(2552 4630);
DISPLAY 0.617021 (2552 4630);
PAINT ORANGE (2552 4630);
WIRE 16 -1 (1100 3675)(525 3675);
FORCEPROP 2 LAST SIG_NAME VR_P5V_STBY_BOOT
J 0
(640 3685);
DISPLAY 0.617021 (640 3685);
PAINT ORANGE (640 3685);
FORCEPROP 2 LASTPROP $XRERR UNIQUE?
J 0
(400 3685);
DISPLAY 0.638298 (400 3685);
PAINT MONO (400 3685);
DISPLAY INVISIBLE (400 3685);
WIRE 16 -1 (1750 3650)(1750 3525);
WIRE 16 -1 (1975 3650)(1750 3650);
FORCEPROP 0 LAST SIG_NAME VR_P5V_STBY_VSENSE_R
J 0
(1415 3660);
DISPLAY 0.617021 (1415 3660);
PAINT ORANGE (1415 3660);
FORCEPROP 2 LASTPROP $XRERR UNIQUE?
J 0
(1175 3660);
DISPLAY 0.638298 (1175 3660);
PAINT MONO (1175 3660);
DISPLAY INVISIBLE (1175 3660);
WIRE 16 -1 (-825 2700)(-825 3325);
FORCEPROP 2 LAST SIG_NAME VR_P5V_STBY_RT
R 1
J 0
(-830 2785);
DISPLAY 0.617021 (-830 2785);
PAINT ORANGE (-830 2785);
FORCEPROP 2 LASTPROP $XRERR UNIQUE?
J 0
(-1070 2785);
DISPLAY 0.638298 (-1070 2785);
PAINT MONO (-1070 2785);
DISPLAY INVISIBLE (-1070 2785);
WIRE 16 -1 (-825 3325)(-275 3325);
WIRE 16 -1 (-375 2200)(-300 2200);
WIRE 16 -1 (-375 2200)(-375 2575);
FORCEPROP 2 LAST SIG_NAME VR_P5V_STBY_COMP
R 1
J 0
(-385 2660);
DISPLAY 0.617021 (-385 2660);
PAINT ORANGE (-385 2660);
FORCEPROP 2 LASTPROP $XRERR UNIQUE?
J 0
(-625 2660);
DISPLAY 0.638298 (-625 2660);
PAINT MONO (-625 2660);
DISPLAY INVISIBLE (-625 2660);
WIRE 16 -1 (100 2575)(-375 2575);
WIRE 16 -1 (-375 2575)(-375 3275);
WIRE 16 -1 (-375 3275)(-275 3275);
WIRE 16 -1 (1500 4500)(1500 4625);
WIRE 16 -1 (1500 4625)(2150 4625);
FORCEPROP 2 LAST SIG_NAME PWRGD_P5V_STBY_R
J 0
(1577 4630);
DISPLAY 0.617021 (1577 4630);
PAINT ORANGE (1577 4630);
FORCEPROP 2 LASTPROP $XRERR UNIQUE?
J 0
(1337 4630);
DISPLAY 0.638298 (1337 4630);
PAINT MONO (1337 4630);
DISPLAY INVISIBLE (1337 4630);
WIRE 16 -1 (1225 4750)(1225 4625);
WIRE 16 -1 (1500 4625)(1225 4625);
WIRE 16 -1 (1225 4625)(1225 3775);
WIRE 16 -1 (525 3775)(1225 3775);
WIRE 16 2175 (2450 2725)(3775 2725);
WIRE 16 -1 (-3250 3475)(-2000 3475);
FORCEPROP 2 LAST SIG_NAME PWRGD_P12V_HSC_DLY
J 0
(-3235 3485);
DISPLAY 0.617021 (-3235 3485);
PAINT ORANGE (-3235 3485);
WIRE 16 -1 (-1725 3475)(-2000 3475);
WIRE 16 -1 (-2000 3175)(-2000 3475);
WIRE 68 -1 (-1850 4050)(-1850 4600);
WIRE 68 -1 (-2450 4600)(-1850 4600);
WIRE 68 -1 (-2450 4050)(-1850 4050);
WIRE 68 -1 (-2450 4050)(-2450 4600);
WIRE 68 -1 (-3125 4025)(-3125 4600);
WIRE 68 -1 (-3125 4600)(-2500 4600);
WIRE 68 -1 (-3125 4025)(-2500 4025);
WIRE 68 -1 (-2500 4025)(-2500 4600);
DOT 1 (-1750 4525);
DOT 1 (-3050 4525);
DOT 1 (-2750 4525);
DOT 1 (-2400 4525);
DOT 1 (-2100 4525);
DOT 1 (-1400 4525);
DOT 1 (1400 3575);
DOT 1 (1400 3675);
DOT 1 (1500 4625);
DOT 1 (1225 4625);
DOT 1 (1750 3150);
DOT 1 (675 3275);
DOT 1 (675 3225);
DOT 1 (975 2200);
DOT 1 (-400 3775);
DOT 1 (-375 2575);
DOT 1 (-925 2350);
DOT 1 (-2000 3475);
DOT 1 (-1400 4025);
DOT 1 (2850 3550);
DOT 1 (3800 3550);
DOT 1 (2850 4050);
DOT 1 (3400 4050);
DOT 1 (3400 3550);
DOT 1 (2550 4050);
DOT 1 (2375 4050);
DOT 1 (3800 4050);
FORCENOTE
PUT TOGETHER
(-3150 4600) 0;
DISPLAY LEFT (-3150 4600);
DISPLAY 0.808511 (-3150 4600);
PAINT PURPLE (-3150 4600);
FORCENOTE
PUT TOGETHER
(-2450 4600) 0;
DISPLAY LEFT (-2450 4600);
DISPLAY 0.808511 (-2450 4600);
PAINT PURPLE (-2450 4600);
FORCENOTE
TP FAB1 CHANGE ONE 47UF CPA TO TWO 22UF CAPS 0107
(-3475 3925) 0;
DISPLAY LEFT (-3475 3925);
DISPLAY 1.021277 (-3475 3925);
PAINT RED (-3475 3925);
FORCENOTE
CONNECT AT SINGLE
(1225 1825) 0;
DISPLAY LEFT (1225 1825);
DISPLAY 1.361702 (1225 1825);
PAINT PURPLE (1225 1825);
FORCENOTE
SPOF
(825 3825) 0;
DISPLAY LEFT (825 3825);
DISPLAY 1.425532 (825 3825);
PAINT PURPLE (825 3825);
FORCENOTE
SPOF
(1888 3122) 0;
DISPLAY LEFT (1888 3122);
DISPLAY 1.595745 (1888 3122);
PAINT PURPLE (1888 3122);
FORCENOTE
POINT ONLY
(1400 1700) 0;
DISPLAY LEFT (1400 1700);
DISPLAY 1.361702 (1400 1700);
PAINT PURPLE (1400 1700);
FORCENOTE
COMPENSATION TYPE II
(-150 2350) 0;
DISPLAY LEFT (-150 2350);
DISPLAY 1.361702 (-150 2350);
PAINT PURPLE (-150 2350);
FORCENOTE
650KHZ
(-800 2825) 0;
DISPLAY LEFT (-800 2825);
DISPLAY 0.872340 (-800 2825);
PAINT PURPLE (-800 2825);
FORCENOTE
BOM_COST=P5V_STBY_VR
(-3535 345) 0;
DISPLAY LEFT (-3535 345);
DISPLAY 2.446809 (-3535 345);
PAINT PURPLE (-3535 345);
FORCENOTE
ROOM=P5V_STBY_VR
(-3535 470) 0;
DISPLAY LEFT (-3535 470);
DISPLAY 2.446809 (-3535 470);
PAINT PURPLE (-3535 470);
FORCENOTE
5.8MS
(-1275 2775) 0;
DISPLAY LEFT (-1275 2775);
DISPLAY 0.872340 (-1275 2775);
PAINT PURPLE (-1275 2775);
FORCENOTE
TP FAB1 CHANGE PN 0331
(3300 3350) 0;
DISPLAY LEFT (3300 3350);
DISPLAY 0.638298 (3300 3350);
PAINT RED (3300 3350);
FORCENOTE
TP FAB1 CHANGE PN 0310
(2750 3300) 0;
DISPLAY LEFT (2750 3300);
DISPLAY 0.638298 (2750 3300);
PAINT RED (2750 3300);
QUIT
